FILE_TYPE = MACRO_DRAWING;
SET COLOR_WIRE YELLOW;
SET COLOR_PROP MONO;
SET COLOR_DOT WHITE;
SET COLOR_ARC YELLOW;
SET COLOR_BODY GREEN;
SET COLOR_NOTE MONO;
SET PROP_DISPLAY VALUE;
SET PAGE_NUMBER P51;
FORCEADD OFFPAGE..3
(1600 5200);
FORCEPROP 2 LAST $XR1 52 
J 0
(1904 5200);
DISPLAY 0.638298 (1904 5200);
PAINT MONO (1904 5200);
FORCEPROP 2 LAST $XR0 27 
J 0
(1814 5200);
DISPLAY 0.638298 (1814 5200);
PAINT MONO (1814 5200);
FORCEPROP 2 LAST CDS_LIB mstr_standard
J 0
(1600 5200);
DISPLAY 0.787234 (1600 5200);
PAINT MONO (1600 5200);
DISPLAY INVISIBLE (1600 5200);
FORCEPROP 1 LAST OFFPAGE TRUE
J 0
(1925 5075);
DISPLAY 0.936170 (1925 5075);
PAINT GREEN (1925 5075);
DISPLAY INVISIBLE (1925 5075);
FORCEPROP 1 LAST COMMENT_BODY TRUE
J 0
(1550 5100);
DISPLAY 0.936170 (1550 5100);
PAINT GREEN (1550 5100);
DISPLAY INVISIBLE (1550 5100);
FORCEPROP 2 LAST PATH I1
J 0
(1800 5275);
DISPLAY 0.787234 (1800 5275);
PAINT MONO (1800 5275);
DISPLAY INVISIBLE (1800 5275);
FORCEADD TAP..6
R 2
(700 5050);
FORCEPROP 3 LASTPIN (650 5050) SIG_NAME M_E_DQS_DP<16>
J 0
(660 5060);
DISPLAY 0.659574 (660 5060);
PAINT MONO (660 5060);
DISPLAY INVISIBLE (660 5060);
FORCEPROP 1 LASTPIN (650 5050) BN 16
J 2
(700 5060);
DISPLAY 0.617021 (700 5060);
PAINT PINK (700 5060);
FORCEPROP 2 LAST CDS_LIB mstr_standard
J 0
(700 5050);
DISPLAY 0.787234 (700 5050);
PAINT MONO (700 5050);
DISPLAY INVISIBLE (700 5050);
FORCEPROP 1 LAST BODY_TYPE PLUMBING
J 2
(700 5000);
DISPLAY 1.234043 (700 5000);
PAINT GREEN (700 5000);
DISPLAY INVISIBLE (700 5000);
FORCEPROP 1 LAST HDL_TAP TRUE
J 2
(375 4925);
DISPLAY 1.234043 (375 4925);
PAINT GREEN (375 4925);
DISPLAY INVISIBLE (375 4925);
FORCEPROP 1 LAST PATH I10
J 2
(700 5050);
DISPLAY 0.936170 (700 5050);
PAINT GREEN (700 5050);
DISPLAY INVISIBLE (700 5050);
FORCEADD TAP..6
R 2
(-1600 2250);
FORCEPROP 3 LASTPIN (-1650 2250) SIG_NAME M_E_DQ<11>
J 0
(-1640 2260);
DISPLAY 0.659574 (-1640 2260);
PAINT MONO (-1640 2260);
DISPLAY INVISIBLE (-1640 2260);
FORCEPROP 1 LASTPIN (-1650 2250) BN 11
J 2
(-1600 2260);
DISPLAY 0.617021 (-1600 2260);
PAINT PINK (-1600 2260);
FORCEPROP 2 LAST CDS_LIB mstr_standard
J 2
(-1600 2250);
DISPLAY 0.787234 (-1600 2250);
PAINT MONO (-1600 2250);
DISPLAY INVISIBLE (-1600 2250);
FORCEPROP 1 LAST BODY_TYPE PLUMBING
J 2
(-1600 2200);
DISPLAY 1.234043 (-1600 2200);
PAINT GREEN (-1600 2200);
DISPLAY INVISIBLE (-1600 2200);
FORCEPROP 1 LAST HDL_TAP TRUE
J 2
(-1925 2125);
DISPLAY 1.234043 (-1925 2125);
PAINT GREEN (-1925 2125);
DISPLAY INVISIBLE (-1925 2125);
FORCEPROP 1 LAST PATH I100
J 2
(-1600 2250);
DISPLAY 0.936170 (-1600 2250);
PAINT GREEN (-1600 2250);
DISPLAY INVISIBLE (-1600 2250);
FORCEADD TAP..6
R 2
(-1600 2200);
FORCEPROP 3 LASTPIN (-1650 2200) SIG_NAME M_E_DQ<8>
J 0
(-1640 2210);
DISPLAY 0.659574 (-1640 2210);
PAINT MONO (-1640 2210);
DISPLAY INVISIBLE (-1640 2210);
FORCEPROP 1 LASTPIN (-1650 2200) BN 8
J 2
(-1600 2210);
DISPLAY 0.617021 (-1600 2210);
PAINT PINK (-1600 2210);
FORCEPROP 2 LAST CDS_LIB mstr_standard
J 2
(-1600 2200);
DISPLAY 0.787234 (-1600 2200);
PAINT MONO (-1600 2200);
DISPLAY INVISIBLE (-1600 2200);
FORCEPROP 1 LAST BODY_TYPE PLUMBING
J 2
(-1600 2150);
DISPLAY 1.234043 (-1600 2150);
PAINT GREEN (-1600 2150);
DISPLAY INVISIBLE (-1600 2150);
FORCEPROP 1 LAST HDL_TAP TRUE
J 2
(-1925 2075);
DISPLAY 1.234043 (-1925 2075);
PAINT GREEN (-1925 2075);
DISPLAY INVISIBLE (-1925 2075);
FORCEPROP 1 LAST PATH I101
J 2
(-1600 2200);
DISPLAY 0.936170 (-1600 2200);
PAINT GREEN (-1600 2200);
DISPLAY INVISIBLE (-1600 2200);
FORCEADD TAP..6
R 2
(-1600 2100);
FORCEPROP 3 LASTPIN (-1650 2100) SIG_NAME M_E_DQ<6>
J 0
(-1640 2110);
DISPLAY 0.659574 (-1640 2110);
PAINT MONO (-1640 2110);
DISPLAY INVISIBLE (-1640 2110);
FORCEPROP 1 LASTPIN (-1650 2100) BN 6
J 2
(-1600 2110);
DISPLAY 0.617021 (-1600 2110);
PAINT PINK (-1600 2110);
FORCEPROP 2 LAST CDS_LIB mstr_standard
J 2
(-1600 2100);
DISPLAY 0.787234 (-1600 2100);
PAINT MONO (-1600 2100);
DISPLAY INVISIBLE (-1600 2100);
FORCEPROP 1 LAST BODY_TYPE PLUMBING
J 2
(-1600 2050);
DISPLAY 1.234043 (-1600 2050);
PAINT GREEN (-1600 2050);
DISPLAY INVISIBLE (-1600 2050);
FORCEPROP 1 LAST HDL_TAP TRUE
J 2
(-1925 1975);
DISPLAY 1.234043 (-1925 1975);
PAINT GREEN (-1925 1975);
DISPLAY INVISIBLE (-1925 1975);
FORCEPROP 1 LAST PATH I102
J 2
(-1600 2100);
DISPLAY 0.936170 (-1600 2100);
PAINT GREEN (-1600 2100);
DISPLAY INVISIBLE (-1600 2100);
FORCEADD TAP..6
R 2
(-1600 2150);
FORCEPROP 3 LASTPIN (-1650 2150) SIG_NAME M_E_DQ<9>
J 0
(-1640 2160);
DISPLAY 0.659574 (-1640 2160);
PAINT MONO (-1640 2160);
DISPLAY INVISIBLE (-1640 2160);
FORCEPROP 1 LASTPIN (-1650 2150) BN 9
J 2
(-1600 2160);
DISPLAY 0.617021 (-1600 2160);
PAINT PINK (-1600 2160);
FORCEPROP 2 LAST CDS_LIB mstr_standard
J 2
(-1600 2150);
DISPLAY 0.787234 (-1600 2150);
PAINT MONO (-1600 2150);
DISPLAY INVISIBLE (-1600 2150);
FORCEPROP 1 LAST BODY_TYPE PLUMBING
J 2
(-1600 2100);
DISPLAY 1.234043 (-1600 2100);
PAINT GREEN (-1600 2100);
DISPLAY INVISIBLE (-1600 2100);
FORCEPROP 1 LAST HDL_TAP TRUE
J 2
(-1925 2025);
DISPLAY 1.234043 (-1925 2025);
PAINT GREEN (-1925 2025);
DISPLAY INVISIBLE (-1925 2025);
FORCEPROP 1 LAST PATH I103
J 2
(-1600 2150);
DISPLAY 0.936170 (-1600 2150);
PAINT GREEN (-1600 2150);
DISPLAY INVISIBLE (-1600 2150);
FORCEADD TAP..6
R 2
(-1600 2050);
FORCEPROP 3 LASTPIN (-1650 2050) SIG_NAME M_E_DQ<7>
J 0
(-1640 2060);
DISPLAY 0.659574 (-1640 2060);
PAINT MONO (-1640 2060);
DISPLAY INVISIBLE (-1640 2060);
FORCEPROP 1 LASTPIN (-1650 2050) BN 7
J 2
(-1600 2060);
DISPLAY 0.617021 (-1600 2060);
PAINT PINK (-1600 2060);
FORCEPROP 2 LAST CDS_LIB mstr_standard
J 2
(-1600 2050);
DISPLAY 0.787234 (-1600 2050);
PAINT MONO (-1600 2050);
DISPLAY INVISIBLE (-1600 2050);
FORCEPROP 1 LAST BODY_TYPE PLUMBING
J 2
(-1600 2000);
DISPLAY 1.234043 (-1600 2000);
PAINT GREEN (-1600 2000);
DISPLAY INVISIBLE (-1600 2000);
FORCEPROP 1 LAST HDL_TAP TRUE
J 2
(-1925 1925);
DISPLAY 1.234043 (-1925 1925);
PAINT GREEN (-1925 1925);
DISPLAY INVISIBLE (-1925 1925);
FORCEPROP 1 LAST PATH I104
J 2
(-1600 2050);
DISPLAY 0.936170 (-1600 2050);
PAINT GREEN (-1600 2050);
DISPLAY INVISIBLE (-1600 2050);
FORCEADD TAP..6
R 2
(-1600 2000);
FORCEPROP 3 LASTPIN (-1650 2000) SIG_NAME M_E_DQ<4>
J 0
(-1640 2010);
DISPLAY 0.659574 (-1640 2010);
PAINT MONO (-1640 2010);
DISPLAY INVISIBLE (-1640 2010);
FORCEPROP 1 LASTPIN (-1650 2000) BN 4
J 2
(-1600 2010);
DISPLAY 0.617021 (-1600 2010);
PAINT PINK (-1600 2010);
FORCEPROP 2 LAST CDS_LIB mstr_standard
J 2
(-1600 2000);
DISPLAY 0.787234 (-1600 2000);
PAINT MONO (-1600 2000);
DISPLAY INVISIBLE (-1600 2000);
FORCEPROP 1 LAST BODY_TYPE PLUMBING
J 2
(-1600 1950);
DISPLAY 1.234043 (-1600 1950);
PAINT GREEN (-1600 1950);
DISPLAY INVISIBLE (-1600 1950);
FORCEPROP 1 LAST HDL_TAP TRUE
J 2
(-1925 1875);
DISPLAY 1.234043 (-1925 1875);
PAINT GREEN (-1925 1875);
DISPLAY INVISIBLE (-1925 1875);
FORCEPROP 1 LAST PATH I105
J 2
(-1600 2000);
DISPLAY 0.936170 (-1600 2000);
PAINT GREEN (-1600 2000);
DISPLAY INVISIBLE (-1600 2000);
FORCEADD TAP..6
R 2
(-1600 1900);
FORCEPROP 3 LASTPIN (-1650 1900) SIG_NAME M_E_DQ<2>
J 0
(-1640 1910);
DISPLAY 0.659574 (-1640 1910);
PAINT MONO (-1640 1910);
DISPLAY INVISIBLE (-1640 1910);
FORCEPROP 1 LASTPIN (-1650 1900) BN 2
J 2
(-1600 1910);
DISPLAY 0.617021 (-1600 1910);
PAINT PINK (-1600 1910);
FORCEPROP 2 LAST CDS_LIB mstr_standard
J 2
(-1600 1900);
DISPLAY 0.787234 (-1600 1900);
PAINT MONO (-1600 1900);
DISPLAY INVISIBLE (-1600 1900);
FORCEPROP 1 LAST BODY_TYPE PLUMBING
J 2
(-1600 1850);
DISPLAY 1.234043 (-1600 1850);
PAINT GREEN (-1600 1850);
DISPLAY INVISIBLE (-1600 1850);
FORCEPROP 1 LAST HDL_TAP TRUE
J 2
(-1925 1775);
DISPLAY 1.234043 (-1925 1775);
PAINT GREEN (-1925 1775);
DISPLAY INVISIBLE (-1925 1775);
FORCEPROP 1 LAST PATH I106
J 2
(-1600 1900);
DISPLAY 0.936170 (-1600 1900);
PAINT GREEN (-1600 1900);
DISPLAY INVISIBLE (-1600 1900);
FORCEADD TAP..6
R 2
(-1600 1950);
FORCEPROP 3 LASTPIN (-1650 1950) SIG_NAME M_E_DQ<5>
J 0
(-1640 1960);
DISPLAY 0.659574 (-1640 1960);
PAINT MONO (-1640 1960);
DISPLAY INVISIBLE (-1640 1960);
FORCEPROP 1 LASTPIN (-1650 1950) BN 5
J 2
(-1600 1960);
DISPLAY 0.617021 (-1600 1960);
PAINT PINK (-1600 1960);
FORCEPROP 2 LAST CDS_LIB mstr_standard
J 2
(-1600 1950);
DISPLAY 0.787234 (-1600 1950);
PAINT MONO (-1600 1950);
DISPLAY INVISIBLE (-1600 1950);
FORCEPROP 1 LAST BODY_TYPE PLUMBING
J 2
(-1600 1900);
DISPLAY 1.234043 (-1600 1900);
PAINT GREEN (-1600 1900);
DISPLAY INVISIBLE (-1600 1900);
FORCEPROP 1 LAST HDL_TAP TRUE
J 2
(-1925 1825);
DISPLAY 1.234043 (-1925 1825);
PAINT GREEN (-1925 1825);
DISPLAY INVISIBLE (-1925 1825);
FORCEPROP 1 LAST PATH I107
J 2
(-1600 1950);
DISPLAY 0.936170 (-1600 1950);
PAINT GREEN (-1600 1950);
DISPLAY INVISIBLE (-1600 1950);
FORCEADD TAP..6
R 2
(-1600 1800);
FORCEPROP 3 LASTPIN (-1650 1800) SIG_NAME M_E_DQ<0>
J 0
(-1640 1810);
DISPLAY 0.659574 (-1640 1810);
PAINT MONO (-1640 1810);
DISPLAY INVISIBLE (-1640 1810);
FORCEPROP 1 LASTPIN (-1650 1800) BN 0
J 2
(-1600 1810);
DISPLAY 0.617021 (-1600 1810);
PAINT PINK (-1600 1810);
FORCEPROP 2 LAST CDS_LIB mstr_standard
J 2
(-1600 1800);
DISPLAY 0.787234 (-1600 1800);
PAINT MONO (-1600 1800);
DISPLAY INVISIBLE (-1600 1800);
FORCEPROP 1 LAST BODY_TYPE PLUMBING
J 2
(-1600 1750);
DISPLAY 1.234043 (-1600 1750);
PAINT GREEN (-1600 1750);
DISPLAY INVISIBLE (-1600 1750);
FORCEPROP 1 LAST HDL_TAP TRUE
J 2
(-1925 1675);
DISPLAY 1.234043 (-1925 1675);
PAINT GREEN (-1925 1675);
DISPLAY INVISIBLE (-1925 1675);
FORCEPROP 1 LAST PATH I108
J 2
(-1600 1800);
DISPLAY 0.936170 (-1600 1800);
PAINT GREEN (-1600 1800);
DISPLAY INVISIBLE (-1600 1800);
FORCEADD TAP..6
R 2
(-1600 1850);
FORCEPROP 3 LASTPIN (-1650 1850) SIG_NAME M_E_DQ<3>
J 0
(-1640 1860);
DISPLAY 0.659574 (-1640 1860);
PAINT MONO (-1640 1860);
DISPLAY INVISIBLE (-1640 1860);
FORCEPROP 1 LASTPIN (-1650 1850) BN 3
J 2
(-1600 1860);
DISPLAY 0.617021 (-1600 1860);
PAINT PINK (-1600 1860);
FORCEPROP 2 LAST CDS_LIB mstr_standard
J 2
(-1600 1850);
DISPLAY 0.787234 (-1600 1850);
PAINT MONO (-1600 1850);
DISPLAY INVISIBLE (-1600 1850);
FORCEPROP 1 LAST BODY_TYPE PLUMBING
J 2
(-1600 1800);
DISPLAY 1.234043 (-1600 1800);
PAINT GREEN (-1600 1800);
DISPLAY INVISIBLE (-1600 1800);
FORCEPROP 1 LAST HDL_TAP TRUE
J 2
(-1925 1725);
DISPLAY 1.234043 (-1925 1725);
PAINT GREEN (-1925 1725);
DISPLAY INVISIBLE (-1925 1725);
FORCEPROP 1 LAST PATH I109
J 2
(-1600 1850);
DISPLAY 0.936170 (-1600 1850);
PAINT GREEN (-1600 1850);
DISPLAY INVISIBLE (-1600 1850);
FORCEADD TAP..6
R 2
(700 4950);
FORCEPROP 3 LASTPIN (650 4950) SIG_NAME M_E_DQS_DP<15>
J 0
(660 4960);
DISPLAY 0.659574 (660 4960);
PAINT MONO (660 4960);
DISPLAY INVISIBLE (660 4960);
FORCEPROP 1 LASTPIN (650 4950) BN 15
J 2
(700 4960);
DISPLAY 0.617021 (700 4960);
PAINT PINK (700 4960);
FORCEPROP 2 LAST CDS_LIB mstr_standard
J 0
(700 4950);
DISPLAY 0.787234 (700 4950);
PAINT MONO (700 4950);
DISPLAY INVISIBLE (700 4950);
FORCEPROP 1 LAST BODY_TYPE PLUMBING
J 2
(700 4900);
DISPLAY 1.234043 (700 4900);
PAINT GREEN (700 4900);
DISPLAY INVISIBLE (700 4900);
FORCEPROP 1 LAST HDL_TAP TRUE
J 2
(375 4825);
DISPLAY 1.234043 (375 4825);
PAINT GREEN (375 4825);
DISPLAY INVISIBLE (375 4825);
FORCEPROP 1 LAST PATH I11
J 2
(700 4950);
DISPLAY 0.936170 (700 4950);
PAINT GREEN (700 4950);
DISPLAY INVISIBLE (700 4950);
FORCEADD TAP..6
R 2
(-1600 1750);
FORCEPROP 3 LASTPIN (-1650 1750) SIG_NAME M_E_DQ<1>
J 0
(-1640 1760);
DISPLAY 0.659574 (-1640 1760);
PAINT MONO (-1640 1760);
DISPLAY INVISIBLE (-1640 1760);
FORCEPROP 1 LASTPIN (-1650 1750) BN 1
J 2
(-1600 1760);
DISPLAY 0.617021 (-1600 1760);
PAINT PINK (-1600 1760);
FORCEPROP 2 LAST CDS_LIB mstr_standard
J 2
(-1600 1750);
DISPLAY 0.787234 (-1600 1750);
PAINT MONO (-1600 1750);
DISPLAY INVISIBLE (-1600 1750);
FORCEPROP 1 LAST BODY_TYPE PLUMBING
J 2
(-1600 1700);
DISPLAY 1.234043 (-1600 1700);
PAINT GREEN (-1600 1700);
DISPLAY INVISIBLE (-1600 1700);
FORCEPROP 1 LAST HDL_TAP TRUE
J 2
(-1925 1625);
DISPLAY 1.234043 (-1925 1625);
PAINT GREEN (-1925 1625);
DISPLAY INVISIBLE (-1925 1625);
FORCEPROP 1 LAST PATH I110
J 2
(-1600 1750);
DISPLAY 0.936170 (-1600 1750);
PAINT GREEN (-1600 1750);
DISPLAY INVISIBLE (-1600 1750);
FORCEADD SCONN288_H44441004..1
(-2350 3250);
FORCEPROP 1 LAST LOCATION J4A2
J 0
(-2800 5150);
DISPLAY 0.617021 (-2800 5150);
PAINT AQUA (-2800 5150);
FORCEPROP 1 LAST MATERIAL SCONN
J 0
(-2800 5100);
DISPLAY 0.617021 (-2800 5100);
PAINT SKYBLUE (-2800 5100);
FORCEPROP 2 LASTPIN (-2850 2100) $PN 284
J 2
(-2860 2110);
DISPLAY 0.617021 (-2860 2110);
PAINT ORANGE (-2860 2110);
FORCEPROP 2 LASTPIN (-2850 1900) $PN 285
J 2
(-2860 1910);
DISPLAY 0.617021 (-2860 1910);
PAINT ORANGE (-2860 1910);
FORCEPROP 2 LASTPIN (-2850 1850) $PN 141
J 2
(-2860 1860);
DISPLAY 0.617021 (-2860 1860);
PAINT ORANGE (-2860 1860);
FORCEPROP 2 LASTPIN (-2850 1450) $PN 230
J 2
(-2860 1460);
DISPLAY 0.617021 (-2860 1460);
PAINT ORANGE (-2860 1460);
FORCEPROP 2 LASTPIN (-2850 2050) $PN 238
J 2
(-2860 2060);
DISPLAY 0.617021 (-2860 2060);
PAINT ORANGE (-2860 2060);
FORCEPROP 2 LASTPIN (-2850 2000) $PN 140
J 2
(-2860 2010);
DISPLAY 0.617021 (-2860 2010);
PAINT ORANGE (-2860 2010);
FORCEPROP 2 LASTPIN (-2850 1950) $PN 139
J 2
(-2860 1960);
DISPLAY 0.617021 (-2860 1960);
PAINT ORANGE (-2860 1960);
FORCEPROP 2 LASTPIN (-2850 3400) $PN 237
J 2
(-2860 3410);
DISPLAY 0.617021 (-2860 3410);
PAINT ORANGE (-2860 3410);
FORCEPROP 2 LASTPIN (-2850 3350) $PN 93
J 2
(-2860 3360);
DISPLAY 0.617021 (-2860 3360);
PAINT ORANGE (-2860 3360);
FORCEPROP 2 LASTPIN (-2850 3300) $PN 89
J 2
(-2860 3310);
DISPLAY 0.617021 (-2860 3310);
PAINT ORANGE (-2860 3310);
FORCEPROP 2 LASTPIN (-2850 3250) $PN 84
J 2
(-2860 3260);
DISPLAY 0.617021 (-2860 3260);
PAINT ORANGE (-2860 3260);
FORCEPROP 2 LASTPIN (-2850 1600) $PN 227
J 2
(-2860 1610);
DISPLAY 0.617021 (-2860 1610);
PAINT ORANGE (-2860 1610);
FORCEPROP 2 LASTPIN (-2850 1550) $PN 205
J 2
(-2860 1560);
DISPLAY 0.617021 (-2860 1560);
PAINT ORANGE (-2860 1560);
FORCEPROP 2 LASTPIN (-2850 2350) $PN 58
J 2
(-2860 2360);
DISPLAY 0.617021 (-2860 2360);
PAINT ORANGE (-2860 2360);
FORCEPROP 2 LASTPIN (-2850 2400) $PN 222
J 2
(-2860 2410);
DISPLAY 0.617021 (-2860 2410);
PAINT ORANGE (-2860 2410);
FORCEPROP 2 LASTPIN (-2850 3000) $PN 91
J 2
(-2860 3010);
DISPLAY 0.617021 (-2860 3010);
PAINT ORANGE (-2860 3010);
FORCEPROP 2 LASTPIN (-2850 2950) $PN 87
J 2
(-2860 2960);
DISPLAY 0.617021 (-2860 2960);
PAINT ORANGE (-2860 2960);
FORCEPROP 2 LASTPIN (-2850 2300) $PN 78
J 2
(-2860 2310);
DISPLAY 0.617021 (-2860 2310);
PAINT ORANGE (-2860 2310);
FORCEPROP 2 LASTPIN (-1850 4900) $PN 280
J 0
(-1840 4910);
DISPLAY 0.617021 (-1840 4910);
PAINT ORANGE (-1840 4910);
FORCEPROP 2 LASTPIN (-1850 4850) $PN 135
J 0
(-1840 4860);
DISPLAY 0.617021 (-1840 4860);
PAINT ORANGE (-1840 4860);
FORCEPROP 2 LASTPIN (-1850 4800) $PN 273
J 0
(-1840 4810);
DISPLAY 0.617021 (-1840 4810);
PAINT ORANGE (-1840 4810);
FORCEPROP 2 LASTPIN (-1850 4750) $PN 128
J 0
(-1840 4760);
DISPLAY 0.617021 (-1840 4760);
PAINT ORANGE (-1840 4760);
FORCEPROP 2 LASTPIN (-1850 4700) $PN 282
J 0
(-1840 4710);
DISPLAY 0.617021 (-1840 4710);
PAINT ORANGE (-1840 4710);
FORCEPROP 2 LASTPIN (-1850 4650) $PN 137
J 0
(-1840 4660);
DISPLAY 0.617021 (-1840 4660);
PAINT ORANGE (-1840 4660);
FORCEPROP 2 LASTPIN (-1850 4600) $PN 275
J 0
(-1840 4610);
DISPLAY 0.617021 (-1840 4610);
PAINT ORANGE (-1840 4610);
FORCEPROP 2 LASTPIN (-1850 4550) $PN 130
J 0
(-1840 4560);
DISPLAY 0.617021 (-1840 4560);
PAINT ORANGE (-1840 4560);
FORCEPROP 2 LASTPIN (-1850 4500) $PN 269
J 0
(-1840 4510);
DISPLAY 0.617021 (-1840 4510);
PAINT ORANGE (-1840 4510);
FORCEPROP 2 LASTPIN (-1850 4450) $PN 124
J 0
(-1840 4460);
DISPLAY 0.617021 (-1840 4460);
PAINT ORANGE (-1840 4460);
FORCEPROP 2 LASTPIN (-1850 4400) $PN 262
J 0
(-1840 4410);
DISPLAY 0.617021 (-1840 4410);
PAINT ORANGE (-1840 4410);
FORCEPROP 2 LASTPIN (-1850 4350) $PN 117
J 0
(-1840 4360);
DISPLAY 0.617021 (-1840 4360);
PAINT ORANGE (-1840 4360);
FORCEPROP 2 LASTPIN (-1850 4300) $PN 271
J 0
(-1840 4310);
DISPLAY 0.617021 (-1840 4310);
PAINT ORANGE (-1840 4310);
FORCEPROP 2 LASTPIN (-1850 4250) $PN 126
J 0
(-1840 4260);
DISPLAY 0.617021 (-1840 4260);
PAINT ORANGE (-1840 4260);
FORCEPROP 2 LASTPIN (-1850 4200) $PN 264
J 0
(-1840 4210);
DISPLAY 0.617021 (-1840 4210);
PAINT ORANGE (-1840 4210);
FORCEPROP 2 LASTPIN (-1850 4150) $PN 119
J 0
(-1840 4160);
DISPLAY 0.617021 (-1840 4160);
PAINT ORANGE (-1840 4160);
FORCEPROP 2 LASTPIN (-1850 4100) $PN 258
J 0
(-1840 4110);
DISPLAY 0.617021 (-1840 4110);
PAINT ORANGE (-1840 4110);
FORCEPROP 2 LASTPIN (-1850 4050) $PN 113
J 0
(-1840 4060);
DISPLAY 0.617021 (-1840 4060);
PAINT ORANGE (-1840 4060);
FORCEPROP 2 LASTPIN (-1850 4000) $PN 251
J 0
(-1840 4010);
DISPLAY 0.617021 (-1840 4010);
PAINT ORANGE (-1840 4010);
FORCEPROP 2 LASTPIN (-1850 3950) $PN 106
J 0
(-1840 3960);
DISPLAY 0.617021 (-1840 3960);
PAINT ORANGE (-1840 3960);
FORCEPROP 2 LASTPIN (-1850 3900) $PN 260
J 0
(-1840 3910);
DISPLAY 0.617021 (-1840 3910);
PAINT ORANGE (-1840 3910);
FORCEPROP 2 LASTPIN (-1850 3850) $PN 115
J 0
(-1840 3860);
DISPLAY 0.617021 (-1840 3860);
PAINT ORANGE (-1840 3860);
FORCEPROP 2 LASTPIN (-1850 3800) $PN 253
J 0
(-1840 3810);
DISPLAY 0.617021 (-1840 3810);
PAINT ORANGE (-1840 3810);
FORCEPROP 2 LASTPIN (-1850 3750) $PN 108
J 0
(-1840 3760);
DISPLAY 0.617021 (-1840 3760);
PAINT ORANGE (-1840 3760);
FORCEPROP 2 LASTPIN (-1850 3700) $PN 247
J 0
(-1840 3710);
DISPLAY 0.617021 (-1840 3710);
PAINT ORANGE (-1840 3710);
FORCEPROP 2 LASTPIN (-1850 3650) $PN 102
J 0
(-1840 3660);
DISPLAY 0.617021 (-1840 3660);
PAINT ORANGE (-1840 3660);
FORCEPROP 2 LASTPIN (-1850 3600) $PN 240
J 0
(-1840 3610);
DISPLAY 0.617021 (-1840 3610);
PAINT ORANGE (-1840 3610);
FORCEPROP 2 LASTPIN (-1850 3550) $PN 95
J 0
(-1840 3560);
DISPLAY 0.617021 (-1840 3560);
PAINT ORANGE (-1840 3560);
FORCEPROP 2 LASTPIN (-1850 3500) $PN 249
J 0
(-1840 3510);
DISPLAY 0.617021 (-1840 3510);
PAINT ORANGE (-1840 3510);
FORCEPROP 2 LASTPIN (-1850 3450) $PN 104
J 0
(-1840 3460);
DISPLAY 0.617021 (-1840 3460);
PAINT ORANGE (-1840 3460);
FORCEPROP 2 LASTPIN (-1850 3400) $PN 242
J 0
(-1840 3410);
DISPLAY 0.617021 (-1840 3410);
PAINT ORANGE (-1840 3410);
FORCEPROP 2 LASTPIN (-1850 3350) $PN 97
J 0
(-1840 3360);
DISPLAY 0.617021 (-1840 3360);
PAINT ORANGE (-1840 3360);
FORCEPROP 2 LASTPIN (-1850 3300) $PN 188
J 0
(-1840 3310);
DISPLAY 0.617021 (-1840 3310);
PAINT ORANGE (-1840 3310);
FORCEPROP 2 LASTPIN (-1850 3250) $PN 43
J 0
(-1840 3260);
DISPLAY 0.617021 (-1840 3260);
PAINT ORANGE (-1840 3260);
FORCEPROP 2 LASTPIN (-1850 3200) $PN 181
J 0
(-1840 3210);
DISPLAY 0.617021 (-1840 3210);
PAINT ORANGE (-1840 3210);
FORCEPROP 2 LASTPIN (-1850 3150) $PN 36
J 0
(-1840 3160);
DISPLAY 0.617021 (-1840 3160);
PAINT ORANGE (-1840 3160);
FORCEPROP 2 LASTPIN (-1850 3100) $PN 190
J 0
(-1840 3110);
DISPLAY 0.617021 (-1840 3110);
PAINT ORANGE (-1840 3110);
FORCEPROP 2 LASTPIN (-1850 3050) $PN 45
J 0
(-1840 3060);
DISPLAY 0.617021 (-1840 3060);
PAINT ORANGE (-1840 3060);
FORCEPROP 2 LASTPIN (-1850 3000) $PN 183
J 0
(-1840 3010);
DISPLAY 0.617021 (-1840 3010);
PAINT ORANGE (-1840 3010);
FORCEPROP 2 LASTPIN (-1850 2950) $PN 38
J 0
(-1840 2960);
DISPLAY 0.617021 (-1840 2960);
PAINT ORANGE (-1840 2960);
FORCEPROP 2 LASTPIN (-1850 2900) $PN 177
J 0
(-1840 2910);
DISPLAY 0.617021 (-1840 2910);
PAINT ORANGE (-1840 2910);
FORCEPROP 2 LASTPIN (-1850 2850) $PN 32
J 0
(-1840 2860);
DISPLAY 0.617021 (-1840 2860);
PAINT ORANGE (-1840 2860);
FORCEPROP 2 LASTPIN (-1850 2800) $PN 170
J 0
(-1840 2810);
DISPLAY 0.617021 (-1840 2810);
PAINT ORANGE (-1840 2810);
FORCEPROP 2 LASTPIN (-1850 2750) $PN 25
J 0
(-1840 2760);
DISPLAY 0.617021 (-1840 2760);
PAINT ORANGE (-1840 2760);
FORCEPROP 2 LASTPIN (-1850 2700) $PN 179
J 0
(-1840 2710);
DISPLAY 0.617021 (-1840 2710);
PAINT ORANGE (-1840 2710);
FORCEPROP 2 LASTPIN (-1850 2650) $PN 34
J 0
(-1840 2660);
DISPLAY 0.617021 (-1840 2660);
PAINT ORANGE (-1840 2660);
FORCEPROP 2 LASTPIN (-1850 2600) $PN 172
J 0
(-1840 2610);
DISPLAY 0.617021 (-1840 2610);
PAINT ORANGE (-1840 2610);
FORCEPROP 2 LASTPIN (-1850 2550) $PN 27
J 0
(-1840 2560);
DISPLAY 0.617021 (-1840 2560);
PAINT ORANGE (-1840 2560);
FORCEPROP 2 LASTPIN (-1850 2500) $PN 166
J 0
(-1840 2510);
DISPLAY 0.617021 (-1840 2510);
PAINT ORANGE (-1840 2510);
FORCEPROP 2 LASTPIN (-1850 2450) $PN 21
J 0
(-1840 2460);
DISPLAY 0.617021 (-1840 2460);
PAINT ORANGE (-1840 2460);
FORCEPROP 2 LASTPIN (-1850 2400) $PN 159
J 0
(-1840 2410);
DISPLAY 0.617021 (-1840 2410);
PAINT ORANGE (-1840 2410);
FORCEPROP 2 LASTPIN (-1850 2350) $PN 14
J 0
(-1840 2360);
DISPLAY 0.617021 (-1840 2360);
PAINT ORANGE (-1840 2360);
FORCEPROP 2 LASTPIN (-1850 2300) $PN 168
J 0
(-1840 2310);
DISPLAY 0.617021 (-1840 2310);
PAINT ORANGE (-1840 2310);
FORCEPROP 2 LASTPIN (-1850 2250) $PN 23
J 0
(-1840 2260);
DISPLAY 0.617021 (-1840 2260);
PAINT ORANGE (-1840 2260);
FORCEPROP 2 LASTPIN (-1850 2000) $PN 148
J 0
(-1840 2010);
DISPLAY 0.617021 (-1840 2010);
PAINT ORANGE (-1840 2010);
FORCEPROP 2 LASTPIN (-1850 1950) $PN 3
J 0
(-1840 1960);
DISPLAY 0.617021 (-1840 1960);
PAINT ORANGE (-1840 1960);
FORCEPROP 2 LASTPIN (-1850 1900) $PN 157
J 0
(-1840 1910);
DISPLAY 0.617021 (-1840 1910);
PAINT ORANGE (-1840 1910);
FORCEPROP 2 LASTPIN (-1850 1850) $PN 12
J 0
(-1840 1860);
DISPLAY 0.617021 (-1840 1860);
PAINT ORANGE (-1840 1860);
FORCEPROP 2 LASTPIN (-1850 1800) $PN 150
J 0
(-1840 1810);
DISPLAY 0.617021 (-1840 1810);
PAINT ORANGE (-1840 1810);
FORCEPROP 2 LASTPIN (-1850 1750) $PN 5
J 0
(-1840 1760);
DISPLAY 0.617021 (-1840 1760);
PAINT ORANGE (-1840 1760);
FORCEPROP 2 LASTPIN (-2850 3150) $PN 203
J 2
(-2860 3160);
DISPLAY 0.617021 (-2860 3160);
PAINT ORANGE (-2860 3160);
FORCEPROP 2 LASTPIN (-2850 3100) $PN 60
J 2
(-2860 3110);
DISPLAY 0.617021 (-2860 3110);
PAINT ORANGE (-2860 3110);
FORCEPROP 2 LASTPIN (-2850 3650) $PN 219
J 2
(-2860 3660);
DISPLAY 0.617021 (-2860 3660);
PAINT ORANGE (-2860 3660);
FORCEPROP 2 LASTPIN (-2850 3600) $PN 74
J 2
(-2860 3610);
DISPLAY 0.617021 (-2860 3610);
PAINT ORANGE (-2860 3610);
FORCEPROP 2 LASTPIN (-2850 3550) $PN 75
J 2
(-2860 3560);
DISPLAY 0.617021 (-2860 3560);
PAINT ORANGE (-2860 3560);
FORCEPROP 2 LASTPIN (-2850 2850) $PN 199
J 2
(-2860 2860);
DISPLAY 0.617021 (-2860 2860);
PAINT ORANGE (-2860 2860);
FORCEPROP 2 LASTPIN (-2850 2800) $PN 54
J 2
(-2860 2810);
DISPLAY 0.617021 (-2860 2810);
PAINT ORANGE (-2860 2810);
FORCEPROP 2 LASTPIN (-2850 2750) $PN 192
J 2
(-2860 2760);
DISPLAY 0.617021 (-2860 2760);
PAINT ORANGE (-2860 2760);
FORCEPROP 2 LASTPIN (-2850 2700) $PN 47
J 2
(-2860 2710);
DISPLAY 0.617021 (-2860 2710);
PAINT ORANGE (-2860 2710);
FORCEPROP 2 LASTPIN (-2850 2650) $PN 201
J 2
(-2860 2660);
DISPLAY 0.617021 (-2860 2660);
PAINT ORANGE (-2860 2660);
FORCEPROP 2 LASTPIN (-2850 2600) $PN 56
J 2
(-2860 2610);
DISPLAY 0.617021 (-2860 2610);
PAINT ORANGE (-2860 2610);
FORCEPROP 2 LASTPIN (-2850 2550) $PN 194
J 2
(-2860 2560);
DISPLAY 0.617021 (-2860 2560);
PAINT ORANGE (-2860 2560);
FORCEPROP 2 LASTPIN (-2850 2500) $PN 49
J 2
(-2860 2510);
DISPLAY 0.617021 (-2860 2510);
PAINT ORANGE (-2860 2510);
FORCEPROP 2 LASTPIN (-2850 3450) $PN 235
J 2
(-2860 3460);
DISPLAY 0.617021 (-2860 3460);
PAINT ORANGE (-2860 3460);
FORCEPROP 2 LASTPIN (-2850 3850) $PN 207
J 2
(-2860 3860);
DISPLAY 0.617021 (-2860 3860);
PAINT ORANGE (-2860 3860);
FORCEPROP 2 LASTPIN (-2850 3800) $PN 63
J 2
(-2860 3810);
DISPLAY 0.617021 (-2860 3810);
PAINT ORANGE (-2860 3810);
FORCEPROP 2 LASTPIN (-2850 3950) $PN 224
J 2
(-2860 3960);
DISPLAY 0.617021 (-2860 3960);
PAINT ORANGE (-2860 3960);
FORCEPROP 2 LASTPIN (-2850 3900) $PN 81
J 2
(-2860 3910);
DISPLAY 0.617021 (-2860 3910);
PAINT ORANGE (-2860 3910);
FORCEPROP 2 LASTPIN (-2850 2250) $PN 208
J 2
(-2860 2260);
DISPLAY 0.617021 (-2860 2260);
PAINT ORANGE (-2860 2260);
FORCEPROP 2 LASTPIN (-2850 2200) $PN 62
J 2
(-2860 2210);
DISPLAY 0.617021 (-2860 2210);
PAINT ORANGE (-2860 2210);
FORCEPROP 2 LASTPIN (-2850 4900) $PN 234
J 2
(-2860 4910);
DISPLAY 0.617021 (-2860 4910);
PAINT ORANGE (-2860 4910);
FORCEPROP 2 LASTPIN (-2850 4800) $PN 86
J 2
(-2860 4810);
DISPLAY 0.617021 (-2860 4810);
PAINT ORANGE (-2860 4810);
FORCEPROP 2 LASTPIN (-2850 4750) $PN 228
J 2
(-2860 4760);
DISPLAY 0.617021 (-2860 4760);
PAINT ORANGE (-2860 4760);
FORCEPROP 2 LASTPIN (-2850 4700) $PN 232
J 2
(-2860 4710);
DISPLAY 0.617021 (-2860 4710);
PAINT ORANGE (-2860 4710);
FORCEPROP 2 LASTPIN (-2850 4650) $PN 65
J 2
(-2860 4660);
DISPLAY 0.617021 (-2860 4660);
PAINT ORANGE (-2860 4660);
FORCEPROP 2 LASTPIN (-2850 4600) $PN 210
J 2
(-2860 4610);
DISPLAY 0.617021 (-2860 4610);
PAINT ORANGE (-2860 4610);
FORCEPROP 2 LASTPIN (-2850 4550) $PN 225
J 2
(-2860 4560);
DISPLAY 0.617021 (-2860 4560);
PAINT ORANGE (-2860 4560);
FORCEPROP 2 LASTPIN (-2850 4500) $PN 66
J 2
(-2860 4510);
DISPLAY 0.617021 (-2860 4510);
PAINT ORANGE (-2860 4510);
FORCEPROP 2 LASTPIN (-2850 4450) $PN 68
J 2
(-2860 4460);
DISPLAY 0.617021 (-2860 4460);
PAINT ORANGE (-2860 4460);
FORCEPROP 2 LASTPIN (-2850 4400) $PN 211
J 2
(-2860 4410);
DISPLAY 0.617021 (-2860 4410);
PAINT ORANGE (-2860 4410);
FORCEPROP 2 LASTPIN (-2850 4350) $PN 69
J 2
(-2860 4360);
DISPLAY 0.617021 (-2860 4360);
PAINT ORANGE (-2860 4360);
FORCEPROP 2 LASTPIN (-2850 4300) $PN 213
J 2
(-2860 4310);
DISPLAY 0.617021 (-2860 4310);
PAINT ORANGE (-2860 4310);
FORCEPROP 2 LASTPIN (-2850 4250) $PN 214
J 2
(-2860 4260);
DISPLAY 0.617021 (-2860 4260);
PAINT ORANGE (-2860 4260);
FORCEPROP 2 LASTPIN (-2850 4200) $PN 71
J 2
(-2860 4210);
DISPLAY 0.617021 (-2860 4210);
PAINT ORANGE (-2860 4210);
FORCEPROP 2 LASTPIN (-2850 4150) $PN 216
J 2
(-2860 4160);
DISPLAY 0.617021 (-2860 4160);
PAINT ORANGE (-2860 4160);
FORCEPROP 2 LASTPIN (-2850 4100) $PN 72
J 2
(-2860 4110);
DISPLAY 0.617021 (-2860 4110);
PAINT ORANGE (-2860 4110);
FORCEPROP 2 LASTPIN (-2850 4050) $PN 79
J 2
(-2860 4060);
DISPLAY 0.617021 (-2860 4060);
PAINT ORANGE (-2860 4060);
FORCEPROP 2 LASTPIN (-2850 1650) $PN 144
J 2
(-2860 1660);
DISPLAY 0.617021 (-2860 1660);
PAINT ORANGE (-2860 1660);
FORCEPROP 2 LASTPIN (-2850 1750) $PN 146
J 2
(-2860 1760);
DISPLAY 0.617021 (-2860 1760);
PAINT ORANGE (-2860 1760);
FORCEPROP 2 LASTPIN (-1850 2050) $PN 10
J 0
(-1840 2060);
DISPLAY 0.617021 (-1840 2060);
PAINT ORANGE (-1840 2060);
FORCEPROP 2 LASTPIN (-1850 2100) $PN 155
J 0
(-1840 2110);
DISPLAY 0.617021 (-1840 2110);
PAINT ORANGE (-1840 2110);
FORCEPROP 2 LASTPIN (-1850 2150) $PN 16
J 0
(-1840 2160);
DISPLAY 0.617021 (-1840 2160);
PAINT ORANGE (-1840 2160);
FORCEPROP 2 LASTPIN (-1850 2200) $PN 161
J 0
(-1840 2210);
DISPLAY 0.617021 (-1840 2210);
PAINT ORANGE (-1840 2210);
FORCEPROP 2 LASTPIN (-2850 4850) $PN 82
J 2
(-2860 4860);
DISPLAY 0.617021 (-2860 4860);
PAINT ORANGE (-2860 4860);
FORCEPROP 1 LAST PART_NUMBER H44441-004
J 0
(-2800 1250);
DISPLAY 0.617021 (-2800 1250);
PAINT BLUE (-2800 1250);
FORCEPROP 2 LASTPIN (-2850 3700) $PN 218
J 2
(-2860 3710);
DISPLAY 0.617021 (-2860 3710);
PAINT ORANGE (-2860 3710);
FORCEPROP 1 LAST PACK_TYPE PIP
J 0
(-2800 5200);
PAINT SKYBLUE (-2800 5200);
DISPLAY INVISIBLE (-2800 5200);
FORCEPROP 2 LAST BOM_COST MEM
J 0
(-2350 3250);
PAINT ORANGE (-2350 3250);
DISPLAY INVISIBLE (-2350 3250);
FORCEPROP 2 LAST CDS_LIB mstr_sconn
J 0
(-2350 3250);
PAINT ORANGE (-2350 3250);
DISPLAY INVISIBLE (-2350 3250);
FORCEPROP 2 LAST SEC_TYPE PIP
J 0
(-2800 5200);
DISPLAY 1.021277 (-2800 5200);
PAINT ORANGE (-2800 5200);
DISPLAY INVISIBLE (-2800 5200);
FORCEPROP 2 LAST SEC 1
J 0
(-2800 5200);
DISPLAY 0.680851 (-2800 5200);
PAINT MONO (-2800 5200);
DISPLAY INVISIBLE (-2800 5200);
FORCEPROP 2 LAST CDS_LOCATION J4A2
J 0
(-2800 5150);
DISPLAY 0.617021 (-2800 5150);
PAINT AQUA (-2800 5150);
DISPLAY INVISIBLE (-2800 5150);
FORCEPROP 1 LAST PATH I111
J 0
(-2350 5100);
PAINT GREEN (-2350 5100);
DISPLAY INVISIBLE (-2350 5100);
FORCEPROP 2 LAST ROOM DDR4_CH_E
J 0
(-2350 3250);
PAINT ORANGE (-2350 3250);
DISPLAY INVISIBLE (-2350 3250);
FORCEADD TAP..6
(-3100 4900);
FORCEPROP 3 LASTPIN (-3050 4900) SIG_NAME M_E_MA<17>
J 0
(-3040 4910);
DISPLAY 0.659574 (-3040 4910);
PAINT MONO (-3040 4910);
DISPLAY INVISIBLE (-3040 4910);
FORCEPROP 1 LASTPIN (-3050 4900) BN 17
J 0
(-3100 4910);
DISPLAY 0.617021 (-3100 4910);
PAINT PINK (-3100 4910);
FORCEPROP 2 LAST CDS_LIB mstr_standard
J 0
(-3100 4900);
DISPLAY 0.787234 (-3100 4900);
PAINT MONO (-3100 4900);
DISPLAY INVISIBLE (-3100 4900);
FORCEPROP 1 LAST BODY_TYPE PLUMBING
J 0
(-3100 4850);
DISPLAY 1.234043 (-3100 4850);
PAINT GREEN (-3100 4850);
DISPLAY INVISIBLE (-3100 4850);
FORCEPROP 1 LAST HDL_TAP TRUE
J 0
(-2775 4775);
DISPLAY 1.234043 (-2775 4775);
PAINT GREEN (-2775 4775);
DISPLAY INVISIBLE (-2775 4775);
FORCEPROP 1 LAST PATH I112
J 0
(-3100 4900);
DISPLAY 0.936170 (-3100 4900);
PAINT GREEN (-3100 4900);
DISPLAY INVISIBLE (-3100 4900);
FORCEADD TAP..6
(-3100 4850);
FORCEPROP 3 LASTPIN (-3050 4850) SIG_NAME M_E_MA<16>
J 0
(-3040 4860);
DISPLAY 0.659574 (-3040 4860);
PAINT MONO (-3040 4860);
DISPLAY INVISIBLE (-3040 4860);
FORCEPROP 1 LASTPIN (-3050 4850) BN 16
J 0
(-3100 4860);
DISPLAY 0.617021 (-3100 4860);
PAINT PINK (-3100 4860);
FORCEPROP 2 LAST CDS_LIB mstr_standard
J 2
(-3100 4850);
DISPLAY 0.787234 (-3100 4850);
PAINT MONO (-3100 4850);
DISPLAY INVISIBLE (-3100 4850);
FORCEPROP 1 LAST BODY_TYPE PLUMBING
J 0
(-3100 4800);
DISPLAY 1.234043 (-3100 4800);
PAINT GREEN (-3100 4800);
DISPLAY INVISIBLE (-3100 4800);
FORCEPROP 1 LAST HDL_TAP TRUE
J 0
(-2775 4725);
DISPLAY 1.234043 (-2775 4725);
PAINT GREEN (-2775 4725);
DISPLAY INVISIBLE (-2775 4725);
FORCEPROP 1 LAST PATH I113
J 0
(-3100 4850);
DISPLAY 0.936170 (-3100 4850);
PAINT GREEN (-3100 4850);
DISPLAY INVISIBLE (-3100 4850);
FORCEADD TAP..6
(-3100 4800);
FORCEPROP 3 LASTPIN (-3050 4800) SIG_NAME M_E_MA<15>
J 0
(-3040 4810);
DISPLAY 0.659574 (-3040 4810);
PAINT MONO (-3040 4810);
DISPLAY INVISIBLE (-3040 4810);
FORCEPROP 1 LASTPIN (-3050 4800) BN 15
J 0
(-3100 4810);
DISPLAY 0.617021 (-3100 4810);
PAINT PINK (-3100 4810);
FORCEPROP 2 LAST CDS_LIB mstr_standard
J 2
(-3100 4800);
DISPLAY 0.787234 (-3100 4800);
PAINT MONO (-3100 4800);
DISPLAY INVISIBLE (-3100 4800);
FORCEPROP 1 LAST BODY_TYPE PLUMBING
J 0
(-3100 4750);
DISPLAY 1.234043 (-3100 4750);
PAINT GREEN (-3100 4750);
DISPLAY INVISIBLE (-3100 4750);
FORCEPROP 1 LAST HDL_TAP TRUE
J 0
(-2775 4675);
DISPLAY 1.234043 (-2775 4675);
PAINT GREEN (-2775 4675);
DISPLAY INVISIBLE (-2775 4675);
FORCEPROP 1 LAST PATH I114
J 0
(-3100 4800);
DISPLAY 0.936170 (-3100 4800);
PAINT GREEN (-3100 4800);
DISPLAY INVISIBLE (-3100 4800);
FORCEADD TAP..6
(-3100 4750);
FORCEPROP 3 LASTPIN (-3050 4750) SIG_NAME M_E_MA<14>
J 0
(-3040 4760);
DISPLAY 0.659574 (-3040 4760);
PAINT MONO (-3040 4760);
DISPLAY INVISIBLE (-3040 4760);
FORCEPROP 1 LASTPIN (-3050 4750) BN 14
J 0
(-3100 4760);
DISPLAY 0.617021 (-3100 4760);
PAINT PINK (-3100 4760);
FORCEPROP 2 LAST CDS_LIB mstr_standard
J 2
(-3100 4750);
DISPLAY 0.787234 (-3100 4750);
PAINT MONO (-3100 4750);
DISPLAY INVISIBLE (-3100 4750);
FORCEPROP 1 LAST BODY_TYPE PLUMBING
J 0
(-3100 4700);
DISPLAY 1.234043 (-3100 4700);
PAINT GREEN (-3100 4700);
DISPLAY INVISIBLE (-3100 4700);
FORCEPROP 1 LAST HDL_TAP TRUE
J 0
(-2775 4625);
DISPLAY 1.234043 (-2775 4625);
PAINT GREEN (-2775 4625);
DISPLAY INVISIBLE (-2775 4625);
FORCEPROP 1 LAST PATH I115
J 0
(-3100 4750);
DISPLAY 0.936170 (-3100 4750);
PAINT GREEN (-3100 4750);
DISPLAY INVISIBLE (-3100 4750);
FORCEADD TAP..6
(-3100 4700);
FORCEPROP 3 LASTPIN (-3050 4700) SIG_NAME M_E_MA<13>
J 0
(-3040 4710);
DISPLAY 0.659574 (-3040 4710);
PAINT MONO (-3040 4710);
DISPLAY INVISIBLE (-3040 4710);
FORCEPROP 1 LASTPIN (-3050 4700) BN 13
J 0
(-3100 4710);
DISPLAY 0.617021 (-3100 4710);
PAINT PINK (-3100 4710);
FORCEPROP 2 LAST CDS_LIB mstr_standard
J 2
(-3100 4700);
DISPLAY 0.787234 (-3100 4700);
PAINT MONO (-3100 4700);
DISPLAY INVISIBLE (-3100 4700);
FORCEPROP 1 LAST BODY_TYPE PLUMBING
J 0
(-3100 4650);
DISPLAY 1.234043 (-3100 4650);
PAINT GREEN (-3100 4650);
DISPLAY INVISIBLE (-3100 4650);
FORCEPROP 1 LAST HDL_TAP TRUE
J 0
(-2775 4575);
DISPLAY 1.234043 (-2775 4575);
PAINT GREEN (-2775 4575);
DISPLAY INVISIBLE (-2775 4575);
FORCEPROP 1 LAST PATH I116
J 0
(-3100 4700);
DISPLAY 0.936170 (-3100 4700);
PAINT GREEN (-3100 4700);
DISPLAY INVISIBLE (-3100 4700);
FORCEADD TAP..6
(-3100 4650);
FORCEPROP 3 LASTPIN (-3050 4650) SIG_NAME M_E_MA<12>
J 0
(-3040 4660);
DISPLAY 0.659574 (-3040 4660);
PAINT MONO (-3040 4660);
DISPLAY INVISIBLE (-3040 4660);
FORCEPROP 1 LASTPIN (-3050 4650) BN 12
J 0
(-3100 4660);
DISPLAY 0.617021 (-3100 4660);
PAINT PINK (-3100 4660);
FORCEPROP 2 LAST CDS_LIB mstr_standard
J 2
(-3100 4650);
DISPLAY 0.787234 (-3100 4650);
PAINT MONO (-3100 4650);
DISPLAY INVISIBLE (-3100 4650);
FORCEPROP 1 LAST BODY_TYPE PLUMBING
J 0
(-3100 4600);
DISPLAY 1.234043 (-3100 4600);
PAINT GREEN (-3100 4600);
DISPLAY INVISIBLE (-3100 4600);
FORCEPROP 1 LAST HDL_TAP TRUE
J 0
(-2775 4525);
DISPLAY 1.234043 (-2775 4525);
PAINT GREEN (-2775 4525);
DISPLAY INVISIBLE (-2775 4525);
FORCEPROP 1 LAST PATH I117
J 0
(-3100 4650);
DISPLAY 0.936170 (-3100 4650);
PAINT GREEN (-3100 4650);
DISPLAY INVISIBLE (-3100 4650);
FORCEADD TAP..6
(-3100 4600);
FORCEPROP 3 LASTPIN (-3050 4600) SIG_NAME M_E_MA<11>
J 0
(-3040 4610);
DISPLAY 0.659574 (-3040 4610);
PAINT MONO (-3040 4610);
DISPLAY INVISIBLE (-3040 4610);
FORCEPROP 1 LASTPIN (-3050 4600) BN 11
J 0
(-3100 4610);
DISPLAY 0.617021 (-3100 4610);
PAINT PINK (-3100 4610);
FORCEPROP 2 LAST CDS_LIB mstr_standard
J 2
(-3100 4600);
DISPLAY 0.787234 (-3100 4600);
PAINT MONO (-3100 4600);
DISPLAY INVISIBLE (-3100 4600);
FORCEPROP 1 LAST BODY_TYPE PLUMBING
J 0
(-3100 4550);
DISPLAY 1.234043 (-3100 4550);
PAINT GREEN (-3100 4550);
DISPLAY INVISIBLE (-3100 4550);
FORCEPROP 1 LAST HDL_TAP TRUE
J 0
(-2775 4475);
DISPLAY 1.234043 (-2775 4475);
PAINT GREEN (-2775 4475);
DISPLAY INVISIBLE (-2775 4475);
FORCEPROP 1 LAST PATH I118
J 0
(-3100 4600);
DISPLAY 0.936170 (-3100 4600);
PAINT GREEN (-3100 4600);
DISPLAY INVISIBLE (-3100 4600);
FORCEADD TAP..6
(-3100 4550);
FORCEPROP 3 LASTPIN (-3050 4550) SIG_NAME M_E_MA<10>
J 0
(-3040 4560);
DISPLAY 0.659574 (-3040 4560);
PAINT MONO (-3040 4560);
DISPLAY INVISIBLE (-3040 4560);
FORCEPROP 1 LASTPIN (-3050 4550) BN 10
J 0
(-3100 4560);
DISPLAY 0.617021 (-3100 4560);
PAINT PINK (-3100 4560);
FORCEPROP 2 LAST CDS_LIB mstr_standard
J 2
(-3100 4550);
DISPLAY 0.787234 (-3100 4550);
PAINT MONO (-3100 4550);
DISPLAY INVISIBLE (-3100 4550);
FORCEPROP 1 LAST BODY_TYPE PLUMBING
J 0
(-3100 4500);
DISPLAY 1.234043 (-3100 4500);
PAINT GREEN (-3100 4500);
DISPLAY INVISIBLE (-3100 4500);
FORCEPROP 1 LAST HDL_TAP TRUE
J 0
(-2775 4425);
DISPLAY 1.234043 (-2775 4425);
PAINT GREEN (-2775 4425);
DISPLAY INVISIBLE (-2775 4425);
FORCEPROP 1 LAST PATH I119
J 0
(-3100 4550);
DISPLAY 0.936170 (-3100 4550);
PAINT GREEN (-3100 4550);
DISPLAY INVISIBLE (-3100 4550);
FORCEADD TAP..6
R 2
(700 4850);
FORCEPROP 3 LASTPIN (650 4850) SIG_NAME M_E_DQS_DP<14>
J 0
(660 4860);
DISPLAY 0.659574 (660 4860);
PAINT MONO (660 4860);
DISPLAY INVISIBLE (660 4860);
FORCEPROP 1 LASTPIN (650 4850) BN 14
J 2
(700 4860);
DISPLAY 0.617021 (700 4860);
PAINT PINK (700 4860);
FORCEPROP 2 LAST CDS_LIB mstr_standard
J 0
(700 4850);
DISPLAY 0.787234 (700 4850);
PAINT MONO (700 4850);
DISPLAY INVISIBLE (700 4850);
FORCEPROP 1 LAST BODY_TYPE PLUMBING
J 2
(700 4800);
DISPLAY 1.234043 (700 4800);
PAINT GREEN (700 4800);
DISPLAY INVISIBLE (700 4800);
FORCEPROP 1 LAST HDL_TAP TRUE
J 2
(375 4725);
DISPLAY 1.234043 (375 4725);
PAINT GREEN (375 4725);
DISPLAY INVISIBLE (375 4725);
FORCEPROP 1 LAST PATH I12
J 2
(700 4850);
DISPLAY 0.936170 (700 4850);
PAINT GREEN (700 4850);
DISPLAY INVISIBLE (700 4850);
FORCEADD TAP..6
(-3100 4500);
FORCEPROP 3 LASTPIN (-3050 4500) SIG_NAME M_E_MA<9>
J 0
(-3040 4510);
DISPLAY 0.659574 (-3040 4510);
PAINT MONO (-3040 4510);
DISPLAY INVISIBLE (-3040 4510);
FORCEPROP 1 LASTPIN (-3050 4500) BN 9
J 0
(-3100 4510);
DISPLAY 0.617021 (-3100 4510);
PAINT PINK (-3100 4510);
FORCEPROP 2 LAST CDS_LIB mstr_standard
J 2
(-3100 4500);
DISPLAY 0.787234 (-3100 4500);
PAINT MONO (-3100 4500);
DISPLAY INVISIBLE (-3100 4500);
FORCEPROP 1 LAST BODY_TYPE PLUMBING
J 0
(-3100 4450);
DISPLAY 1.234043 (-3100 4450);
PAINT GREEN (-3100 4450);
DISPLAY INVISIBLE (-3100 4450);
FORCEPROP 1 LAST HDL_TAP TRUE
J 0
(-2775 4375);
DISPLAY 1.234043 (-2775 4375);
PAINT GREEN (-2775 4375);
DISPLAY INVISIBLE (-2775 4375);
FORCEPROP 1 LAST PATH I120
J 0
(-3100 4500);
DISPLAY 0.936170 (-3100 4500);
PAINT GREEN (-3100 4500);
DISPLAY INVISIBLE (-3100 4500);
FORCEADD TAP..6
(-3100 4450);
FORCEPROP 3 LASTPIN (-3050 4450) SIG_NAME M_E_MA<8>
J 0
(-3040 4460);
DISPLAY 0.659574 (-3040 4460);
PAINT MONO (-3040 4460);
DISPLAY INVISIBLE (-3040 4460);
FORCEPROP 1 LASTPIN (-3050 4450) BN 8
J 0
(-3100 4460);
DISPLAY 0.617021 (-3100 4460);
PAINT PINK (-3100 4460);
FORCEPROP 2 LAST CDS_LIB mstr_standard
J 2
(-3100 4450);
DISPLAY 0.787234 (-3100 4450);
PAINT MONO (-3100 4450);
DISPLAY INVISIBLE (-3100 4450);
FORCEPROP 1 LAST BODY_TYPE PLUMBING
J 0
(-3100 4400);
DISPLAY 1.234043 (-3100 4400);
PAINT GREEN (-3100 4400);
DISPLAY INVISIBLE (-3100 4400);
FORCEPROP 1 LAST HDL_TAP TRUE
J 0
(-2775 4325);
DISPLAY 1.234043 (-2775 4325);
PAINT GREEN (-2775 4325);
DISPLAY INVISIBLE (-2775 4325);
FORCEPROP 1 LAST PATH I121
J 0
(-3100 4450);
DISPLAY 0.936170 (-3100 4450);
PAINT GREEN (-3100 4450);
DISPLAY INVISIBLE (-3100 4450);
FORCEADD TAP..6
(-3100 4400);
FORCEPROP 3 LASTPIN (-3050 4400) SIG_NAME M_E_MA<7>
J 0
(-3040 4410);
DISPLAY 0.659574 (-3040 4410);
PAINT MONO (-3040 4410);
DISPLAY INVISIBLE (-3040 4410);
FORCEPROP 1 LASTPIN (-3050 4400) BN 7
J 0
(-3100 4410);
DISPLAY 0.617021 (-3100 4410);
PAINT PINK (-3100 4410);
FORCEPROP 2 LAST CDS_LIB mstr_standard
J 2
(-3100 4400);
DISPLAY 0.787234 (-3100 4400);
PAINT MONO (-3100 4400);
DISPLAY INVISIBLE (-3100 4400);
FORCEPROP 1 LAST BODY_TYPE PLUMBING
J 0
(-3100 4350);
DISPLAY 1.234043 (-3100 4350);
PAINT GREEN (-3100 4350);
DISPLAY INVISIBLE (-3100 4350);
FORCEPROP 1 LAST HDL_TAP TRUE
J 0
(-2775 4275);
DISPLAY 1.234043 (-2775 4275);
PAINT GREEN (-2775 4275);
DISPLAY INVISIBLE (-2775 4275);
FORCEPROP 1 LAST PATH I122
J 0
(-3100 4400);
DISPLAY 0.936170 (-3100 4400);
PAINT GREEN (-3100 4400);
DISPLAY INVISIBLE (-3100 4400);
FORCEADD TAP..6
(-3100 4350);
FORCEPROP 3 LASTPIN (-3050 4350) SIG_NAME M_E_MA<6>
J 0
(-3040 4360);
DISPLAY 0.659574 (-3040 4360);
PAINT MONO (-3040 4360);
DISPLAY INVISIBLE (-3040 4360);
FORCEPROP 1 LASTPIN (-3050 4350) BN 6
J 0
(-3100 4360);
DISPLAY 0.617021 (-3100 4360);
PAINT PINK (-3100 4360);
FORCEPROP 2 LAST CDS_LIB mstr_standard
J 2
(-3100 4350);
DISPLAY 0.787234 (-3100 4350);
PAINT MONO (-3100 4350);
DISPLAY INVISIBLE (-3100 4350);
FORCEPROP 1 LAST BODY_TYPE PLUMBING
J 0
(-3100 4300);
DISPLAY 1.234043 (-3100 4300);
PAINT GREEN (-3100 4300);
DISPLAY INVISIBLE (-3100 4300);
FORCEPROP 1 LAST HDL_TAP TRUE
J 0
(-2775 4225);
DISPLAY 1.234043 (-2775 4225);
PAINT GREEN (-2775 4225);
DISPLAY INVISIBLE (-2775 4225);
FORCEPROP 1 LAST PATH I123
J 0
(-3100 4350);
DISPLAY 0.936170 (-3100 4350);
PAINT GREEN (-3100 4350);
DISPLAY INVISIBLE (-3100 4350);
FORCEADD TAP..6
(-3100 4300);
FORCEPROP 3 LASTPIN (-3050 4300) SIG_NAME M_E_MA<5>
J 0
(-3040 4310);
DISPLAY 0.659574 (-3040 4310);
PAINT MONO (-3040 4310);
DISPLAY INVISIBLE (-3040 4310);
FORCEPROP 1 LASTPIN (-3050 4300) BN 5
J 0
(-3100 4310);
DISPLAY 0.617021 (-3100 4310);
PAINT PINK (-3100 4310);
FORCEPROP 2 LAST CDS_LIB mstr_standard
J 2
(-3100 4300);
DISPLAY 0.787234 (-3100 4300);
PAINT MONO (-3100 4300);
DISPLAY INVISIBLE (-3100 4300);
FORCEPROP 1 LAST BODY_TYPE PLUMBING
J 0
(-3100 4250);
DISPLAY 1.234043 (-3100 4250);
PAINT GREEN (-3100 4250);
DISPLAY INVISIBLE (-3100 4250);
FORCEPROP 1 LAST HDL_TAP TRUE
J 0
(-2775 4175);
DISPLAY 1.234043 (-2775 4175);
PAINT GREEN (-2775 4175);
DISPLAY INVISIBLE (-2775 4175);
FORCEPROP 1 LAST PATH I124
J 0
(-3100 4300);
DISPLAY 0.936170 (-3100 4300);
PAINT GREEN (-3100 4300);
DISPLAY INVISIBLE (-3100 4300);
FORCEADD TAP..6
(-3100 4250);
FORCEPROP 3 LASTPIN (-3050 4250) SIG_NAME M_E_MA<4>
J 0
(-3040 4260);
DISPLAY 0.659574 (-3040 4260);
PAINT MONO (-3040 4260);
DISPLAY INVISIBLE (-3040 4260);
FORCEPROP 1 LASTPIN (-3050 4250) BN 4
J 0
(-3100 4260);
DISPLAY 0.617021 (-3100 4260);
PAINT PINK (-3100 4260);
FORCEPROP 2 LAST CDS_LIB mstr_standard
J 2
(-3100 4250);
DISPLAY 0.787234 (-3100 4250);
PAINT MONO (-3100 4250);
DISPLAY INVISIBLE (-3100 4250);
FORCEPROP 1 LAST BODY_TYPE PLUMBING
J 0
(-3100 4200);
DISPLAY 1.234043 (-3100 4200);
PAINT GREEN (-3100 4200);
DISPLAY INVISIBLE (-3100 4200);
FORCEPROP 1 LAST HDL_TAP TRUE
J 0
(-2775 4125);
DISPLAY 1.234043 (-2775 4125);
PAINT GREEN (-2775 4125);
DISPLAY INVISIBLE (-2775 4125);
FORCEPROP 1 LAST PATH I125
J 0
(-3100 4250);
DISPLAY 0.936170 (-3100 4250);
PAINT GREEN (-3100 4250);
DISPLAY INVISIBLE (-3100 4250);
FORCEADD TAP..6
(-3100 4200);
FORCEPROP 3 LASTPIN (-3050 4200) SIG_NAME M_E_MA<3>
J 0
(-3040 4210);
DISPLAY 0.659574 (-3040 4210);
PAINT MONO (-3040 4210);
DISPLAY INVISIBLE (-3040 4210);
FORCEPROP 1 LASTPIN (-3050 4200) BN 3
J 0
(-3100 4210);
DISPLAY 0.617021 (-3100 4210);
PAINT PINK (-3100 4210);
FORCEPROP 2 LAST CDS_LIB mstr_standard
J 2
(-3100 4200);
DISPLAY 0.787234 (-3100 4200);
PAINT MONO (-3100 4200);
DISPLAY INVISIBLE (-3100 4200);
FORCEPROP 1 LAST BODY_TYPE PLUMBING
J 0
(-3100 4150);
DISPLAY 1.234043 (-3100 4150);
PAINT GREEN (-3100 4150);
DISPLAY INVISIBLE (-3100 4150);
FORCEPROP 1 LAST HDL_TAP TRUE
J 0
(-2775 4075);
DISPLAY 1.234043 (-2775 4075);
PAINT GREEN (-2775 4075);
DISPLAY INVISIBLE (-2775 4075);
FORCEPROP 1 LAST PATH I126
J 0
(-3100 4200);
DISPLAY 0.936170 (-3100 4200);
PAINT GREEN (-3100 4200);
DISPLAY INVISIBLE (-3100 4200);
FORCEADD TAP..6
(-3100 4150);
FORCEPROP 3 LASTPIN (-3050 4150) SIG_NAME M_E_MA<2>
J 0
(-3040 4160);
DISPLAY 0.659574 (-3040 4160);
PAINT MONO (-3040 4160);
DISPLAY INVISIBLE (-3040 4160);
FORCEPROP 1 LASTPIN (-3050 4150) BN 2
J 0
(-3100 4160);
DISPLAY 0.617021 (-3100 4160);
PAINT PINK (-3100 4160);
FORCEPROP 2 LAST CDS_LIB mstr_standard
J 2
(-3100 4150);
DISPLAY 0.787234 (-3100 4150);
PAINT MONO (-3100 4150);
DISPLAY INVISIBLE (-3100 4150);
FORCEPROP 1 LAST BODY_TYPE PLUMBING
J 0
(-3100 4100);
DISPLAY 1.234043 (-3100 4100);
PAINT GREEN (-3100 4100);
DISPLAY INVISIBLE (-3100 4100);
FORCEPROP 1 LAST HDL_TAP TRUE
J 0
(-2775 4025);
DISPLAY 1.234043 (-2775 4025);
PAINT GREEN (-2775 4025);
DISPLAY INVISIBLE (-2775 4025);
FORCEPROP 1 LAST PATH I127
J 0
(-3100 4150);
DISPLAY 0.936170 (-3100 4150);
PAINT GREEN (-3100 4150);
DISPLAY INVISIBLE (-3100 4150);
FORCEADD TAP..6
(-3100 4100);
FORCEPROP 3 LASTPIN (-3050 4100) SIG_NAME M_E_MA<1>
J 0
(-3040 4110);
DISPLAY 0.659574 (-3040 4110);
PAINT MONO (-3040 4110);
DISPLAY INVISIBLE (-3040 4110);
FORCEPROP 1 LASTPIN (-3050 4100) BN 1
J 0
(-3100 4110);
DISPLAY 0.617021 (-3100 4110);
PAINT PINK (-3100 4110);
FORCEPROP 2 LAST CDS_LIB mstr_standard
J 2
(-3100 4100);
DISPLAY 0.787234 (-3100 4100);
PAINT MONO (-3100 4100);
DISPLAY INVISIBLE (-3100 4100);
FORCEPROP 1 LAST BODY_TYPE PLUMBING
J 0
(-3100 4050);
DISPLAY 1.234043 (-3100 4050);
PAINT GREEN (-3100 4050);
DISPLAY INVISIBLE (-3100 4050);
FORCEPROP 1 LAST HDL_TAP TRUE
J 0
(-2775 3975);
DISPLAY 1.234043 (-2775 3975);
PAINT GREEN (-2775 3975);
DISPLAY INVISIBLE (-2775 3975);
FORCEPROP 1 LAST PATH I128
J 0
(-3100 4100);
DISPLAY 0.936170 (-3100 4100);
PAINT GREEN (-3100 4100);
DISPLAY INVISIBLE (-3100 4100);
FORCEADD TAP..6
(-3100 4050);
FORCEPROP 3 LASTPIN (-3050 4050) SIG_NAME M_E_MA<0>
J 0
(-3040 4060);
DISPLAY 0.659574 (-3040 4060);
PAINT MONO (-3040 4060);
DISPLAY INVISIBLE (-3040 4060);
FORCEPROP 1 LASTPIN (-3050 4050) BN 0
J 0
(-3100 4060);
DISPLAY 0.617021 (-3100 4060);
PAINT PINK (-3100 4060);
FORCEPROP 2 LAST CDS_LIB mstr_standard
J 2
(-3100 4050);
DISPLAY 0.787234 (-3100 4050);
PAINT MONO (-3100 4050);
DISPLAY INVISIBLE (-3100 4050);
FORCEPROP 1 LAST BODY_TYPE PLUMBING
J 0
(-3100 4000);
DISPLAY 1.234043 (-3100 4000);
PAINT GREEN (-3100 4000);
DISPLAY INVISIBLE (-3100 4000);
FORCEPROP 1 LAST HDL_TAP TRUE
J 0
(-2775 3925);
DISPLAY 1.234043 (-2775 3925);
PAINT GREEN (-2775 3925);
DISPLAY INVISIBLE (-2775 3925);
FORCEPROP 1 LAST PATH I129
J 0
(-3100 4050);
DISPLAY 0.936170 (-3100 4050);
PAINT GREEN (-3100 4050);
DISPLAY INVISIBLE (-3100 4050);
FORCEADD TAP..6
R 2
(700 4750);
FORCEPROP 3 LASTPIN (650 4750) SIG_NAME M_E_DQS_DP<13>
J 0
(660 4760);
DISPLAY 0.659574 (660 4760);
PAINT MONO (660 4760);
DISPLAY INVISIBLE (660 4760);
FORCEPROP 1 LASTPIN (650 4750) BN 13
J 2
(700 4760);
DISPLAY 0.617021 (700 4760);
PAINT PINK (700 4760);
FORCEPROP 2 LAST CDS_LIB mstr_standard
J 0
(700 4750);
DISPLAY 0.787234 (700 4750);
PAINT MONO (700 4750);
DISPLAY INVISIBLE (700 4750);
FORCEPROP 1 LAST BODY_TYPE PLUMBING
J 2
(700 4700);
DISPLAY 1.234043 (700 4700);
PAINT GREEN (700 4700);
DISPLAY INVISIBLE (700 4700);
FORCEPROP 1 LAST HDL_TAP TRUE
J 2
(375 4625);
DISPLAY 1.234043 (375 4625);
PAINT GREEN (375 4625);
DISPLAY INVISIBLE (375 4625);
FORCEPROP 1 LAST PATH I13
J 2
(700 4750);
DISPLAY 0.936170 (700 4750);
PAINT GREEN (700 4750);
DISPLAY INVISIBLE (700 4750);
FORCEADD TAP..6
(-3100 3950);
FORCEPROP 3 LASTPIN (-3050 3950) SIG_NAME M_E_BA<1>
J 0
(-3040 3960);
DISPLAY 0.659574 (-3040 3960);
PAINT MONO (-3040 3960);
DISPLAY INVISIBLE (-3040 3960);
FORCEPROP 1 LASTPIN (-3050 3950) BN 1
J 0
(-3100 3960);
DISPLAY 0.617021 (-3100 3960);
PAINT PINK (-3100 3960);
FORCEPROP 2 LAST CDS_LIB mstr_standard
J 0
(-3100 3950);
DISPLAY 0.787234 (-3100 3950);
PAINT MONO (-3100 3950);
DISPLAY INVISIBLE (-3100 3950);
FORCEPROP 1 LAST BODY_TYPE PLUMBING
J 0
(-3100 3900);
DISPLAY 1.234043 (-3100 3900);
PAINT GREEN (-3100 3900);
DISPLAY INVISIBLE (-3100 3900);
FORCEPROP 1 LAST HDL_TAP TRUE
J 0
(-2775 3825);
DISPLAY 1.234043 (-2775 3825);
PAINT GREEN (-2775 3825);
DISPLAY INVISIBLE (-2775 3825);
FORCEPROP 1 LAST PATH I130
J 0
(-3100 3950);
DISPLAY 0.936170 (-3100 3950);
PAINT GREEN (-3100 3950);
DISPLAY INVISIBLE (-3100 3950);
FORCEADD OFFPAGE..1
(-3900 4950);
FORCEPROP 2 LAST $XR1 52 
J 0
(-4211 4950);
DISPLAY 0.638298 (-4211 4950);
PAINT MONO (-4211 4950);
FORCEPROP 2 LAST $XR0 27 
J 0
(-4121 4950);
DISPLAY 0.638298 (-4121 4950);
PAINT MONO (-4121 4950);
FORCEPROP 2 LAST CDS_LIB mstr_standard
J 0
(-3900 4950);
DISPLAY 0.787234 (-3900 4950);
PAINT MONO (-3900 4950);
DISPLAY INVISIBLE (-3900 4950);
FORCEPROP 1 LAST OFFPAGE TRUE
J 0
(-3575 4825);
DISPLAY 0.936170 (-3575 4825);
PAINT GREEN (-3575 4825);
DISPLAY INVISIBLE (-3575 4825);
FORCEPROP 1 LAST COMMENT_BODY TRUE
J 0
(-3775 4850);
DISPLAY 0.936170 (-3775 4850);
PAINT GREEN (-3775 4850);
DISPLAY INVISIBLE (-3775 4850);
FORCEPROP 2 LAST PATH I131
J 0
(-3850 5025);
DISPLAY 0.787234 (-3850 5025);
PAINT MONO (-3850 5025);
DISPLAY INVISIBLE (-3850 5025);
FORCEADD OFFPAGE..1
(-3900 4050);
FORCEPROP 2 LAST $XR1 52 
J 0
(-4211 4050);
DISPLAY 0.638298 (-4211 4050);
PAINT MONO (-4211 4050);
FORCEPROP 2 LAST $XR0 27 
J 0
(-4121 4050);
DISPLAY 0.638298 (-4121 4050);
PAINT MONO (-4121 4050);
FORCEPROP 2 LAST CDS_LIB mstr_standard
J 0
(-3900 4050);
DISPLAY 0.787234 (-3900 4050);
PAINT MONO (-3900 4050);
DISPLAY INVISIBLE (-3900 4050);
FORCEPROP 1 LAST OFFPAGE TRUE
J 0
(-3575 3925);
DISPLAY 0.936170 (-3575 3925);
PAINT GREEN (-3575 3925);
DISPLAY INVISIBLE (-3575 3925);
FORCEPROP 1 LAST COMMENT_BODY TRUE
J 0
(-3775 3950);
DISPLAY 0.936170 (-3775 3950);
PAINT GREEN (-3775 3950);
DISPLAY INVISIBLE (-3775 3950);
FORCEPROP 2 LAST PATH I132
J 0
(-3850 4125);
DISPLAY 0.787234 (-3850 4125);
PAINT MONO (-3850 4125);
DISPLAY INVISIBLE (-3850 4125);
FORCEADD TAP..6
(-3100 3900);
FORCEPROP 3 LASTPIN (-3050 3900) SIG_NAME M_E_BA<0>
J 0
(-3040 3910);
DISPLAY 0.659574 (-3040 3910);
PAINT MONO (-3040 3910);
DISPLAY INVISIBLE (-3040 3910);
FORCEPROP 1 LASTPIN (-3050 3900) BN 0
J 0
(-3100 3910);
DISPLAY 0.617021 (-3100 3910);
PAINT PINK (-3100 3910);
FORCEPROP 2 LAST CDS_LIB mstr_standard
J 0
(-3100 3900);
DISPLAY 0.787234 (-3100 3900);
PAINT MONO (-3100 3900);
DISPLAY INVISIBLE (-3100 3900);
FORCEPROP 1 LAST BODY_TYPE PLUMBING
J 0
(-3100 3850);
DISPLAY 1.234043 (-3100 3850);
PAINT GREEN (-3100 3850);
DISPLAY INVISIBLE (-3100 3850);
FORCEPROP 1 LAST HDL_TAP TRUE
J 0
(-2775 3775);
DISPLAY 1.234043 (-2775 3775);
PAINT GREEN (-2775 3775);
DISPLAY INVISIBLE (-2775 3775);
FORCEPROP 1 LAST PATH I133
J 0
(-3100 3900);
DISPLAY 0.936170 (-3100 3900);
PAINT GREEN (-3100 3900);
DISPLAY INVISIBLE (-3100 3900);
FORCEADD TAP..6
(-3100 3850);
FORCEPROP 3 LASTPIN (-3050 3850) SIG_NAME M_E_BG<1>
J 0
(-3040 3860);
DISPLAY 0.659574 (-3040 3860);
PAINT MONO (-3040 3860);
DISPLAY INVISIBLE (-3040 3860);
FORCEPROP 1 LASTPIN (-3050 3850) BN 1
J 0
(-3100 3860);
DISPLAY 0.617021 (-3100 3860);
PAINT PINK (-3100 3860);
FORCEPROP 2 LAST CDS_LIB mstr_standard
J 0
(-3100 3850);
DISPLAY 0.787234 (-3100 3850);
PAINT MONO (-3100 3850);
DISPLAY INVISIBLE (-3100 3850);
FORCEPROP 1 LAST BODY_TYPE PLUMBING
J 0
(-3100 3800);
DISPLAY 1.234043 (-3100 3800);
PAINT GREEN (-3100 3800);
DISPLAY INVISIBLE (-3100 3800);
FORCEPROP 1 LAST HDL_TAP TRUE
J 0
(-2775 3725);
DISPLAY 1.234043 (-2775 3725);
PAINT GREEN (-2775 3725);
DISPLAY INVISIBLE (-2775 3725);
FORCEPROP 1 LAST PATH I134
J 0
(-3100 3850);
DISPLAY 0.936170 (-3100 3850);
PAINT GREEN (-3100 3850);
DISPLAY INVISIBLE (-3100 3850);
FORCEADD TAP..6
(-3100 3800);
FORCEPROP 3 LASTPIN (-3050 3800) SIG_NAME M_E_BG<0>
J 0
(-3040 3810);
DISPLAY 0.659574 (-3040 3810);
PAINT MONO (-3040 3810);
DISPLAY INVISIBLE (-3040 3810);
FORCEPROP 1 LASTPIN (-3050 3800) BN 0
J 0
(-3100 3810);
DISPLAY 0.617021 (-3100 3810);
PAINT PINK (-3100 3810);
FORCEPROP 2 LAST CDS_LIB mstr_standard
J 0
(-3100 3800);
DISPLAY 0.787234 (-3100 3800);
PAINT MONO (-3100 3800);
DISPLAY INVISIBLE (-3100 3800);
FORCEPROP 1 LAST BODY_TYPE PLUMBING
J 0
(-3100 3750);
DISPLAY 1.234043 (-3100 3750);
PAINT GREEN (-3100 3750);
DISPLAY INVISIBLE (-3100 3750);
FORCEPROP 1 LAST HDL_TAP TRUE
J 0
(-2775 3675);
DISPLAY 1.234043 (-2775 3675);
PAINT GREEN (-2775 3675);
DISPLAY INVISIBLE (-2775 3675);
FORCEPROP 1 LAST PATH I135
J 0
(-3100 3800);
DISPLAY 0.936170 (-3100 3800);
PAINT GREEN (-3100 3800);
DISPLAY INVISIBLE (-3100 3800);
FORCEADD OFFPAGE..1
(-3900 3500);
FORCEPROP 2 LAST $XR1 52 
J 0
(-4211 3500);
DISPLAY 0.638298 (-4211 3500);
PAINT MONO (-4211 3500);
FORCEPROP 2 LAST $XR0 27 
J 0
(-4121 3500);
DISPLAY 0.638298 (-4121 3500);
PAINT MONO (-4121 3500);
FORCEPROP 2 LAST CDS_LIB mstr_standard
J 0
(-3900 3500);
DISPLAY 0.787234 (-3900 3500);
PAINT MONO (-3900 3500);
DISPLAY INVISIBLE (-3900 3500);
FORCEPROP 1 LAST OFFPAGE TRUE
J 0
(-3575 3375);
DISPLAY 0.936170 (-3575 3375);
PAINT GREEN (-3575 3375);
DISPLAY INVISIBLE (-3575 3375);
FORCEPROP 1 LAST COMMENT_BODY TRUE
J 0
(-3775 3400);
DISPLAY 0.936170 (-3775 3400);
PAINT GREEN (-3775 3400);
DISPLAY INVISIBLE (-3775 3400);
FORCEPROP 2 LAST PATH I136
J 0
(-3850 3575);
DISPLAY 0.787234 (-3850 3575);
PAINT MONO (-3850 3575);
DISPLAY INVISIBLE (-3850 3575);
FORCEADD OFFPAGE..1
(-3900 3900);
FORCEPROP 2 LAST $XR1 52 
J 0
(-4211 3900);
DISPLAY 0.638298 (-4211 3900);
PAINT MONO (-4211 3900);
FORCEPROP 2 LAST $XR0 27 
J 0
(-4121 3900);
DISPLAY 0.638298 (-4121 3900);
PAINT MONO (-4121 3900);
FORCEPROP 2 LAST CDS_LIB mstr_standard
J 0
(-3900 3900);
DISPLAY 0.787234 (-3900 3900);
PAINT MONO (-3900 3900);
DISPLAY INVISIBLE (-3900 3900);
FORCEPROP 1 LAST OFFPAGE TRUE
J 0
(-3575 3775);
DISPLAY 0.936170 (-3575 3775);
PAINT GREEN (-3575 3775);
DISPLAY INVISIBLE (-3575 3775);
FORCEPROP 1 LAST COMMENT_BODY TRUE
J 0
(-3775 3800);
DISPLAY 0.936170 (-3775 3800);
PAINT GREEN (-3775 3800);
DISPLAY INVISIBLE (-3775 3800);
FORCEPROP 2 LAST PATH I137
J 0
(-3850 3975);
DISPLAY 0.787234 (-3850 3975);
PAINT MONO (-3850 3975);
DISPLAY INVISIBLE (-3850 3975);
FORCEADD TAP..6
(-3100 2800);
FORCEPROP 3 LASTPIN (-3050 2800) SIG_NAME M_E_ECC<7>
J 0
(-3040 2810);
DISPLAY 0.659574 (-3040 2810);
PAINT MONO (-3040 2810);
DISPLAY INVISIBLE (-3040 2810);
FORCEPROP 1 LASTPIN (-3050 2800) BN 7
J 0
(-3100 2810);
DISPLAY 0.617021 (-3100 2810);
PAINT PINK (-3100 2810);
FORCEPROP 2 LAST CDS_LIB mstr_standard
J 0
(-3100 2800);
DISPLAY 0.787234 (-3100 2800);
PAINT MONO (-3100 2800);
DISPLAY INVISIBLE (-3100 2800);
FORCEPROP 1 LAST BODY_TYPE PLUMBING
J 0
(-3100 2750);
DISPLAY 1.234043 (-3100 2750);
PAINT GREEN (-3100 2750);
DISPLAY INVISIBLE (-3100 2750);
FORCEPROP 1 LAST HDL_TAP TRUE
J 0
(-2775 2675);
DISPLAY 1.234043 (-2775 2675);
PAINT GREEN (-2775 2675);
DISPLAY INVISIBLE (-2775 2675);
FORCEPROP 1 LAST PATH I138
J 0
(-3100 2800);
DISPLAY 0.936170 (-3100 2800);
PAINT GREEN (-3100 2800);
DISPLAY INVISIBLE (-3100 2800);
FORCEADD TAP..6
(-3100 2850);
FORCEPROP 3 LASTPIN (-3050 2850) SIG_NAME M_E_ECC<6>
J 0
(-3040 2860);
DISPLAY 0.659574 (-3040 2860);
PAINT MONO (-3040 2860);
DISPLAY INVISIBLE (-3040 2860);
FORCEPROP 1 LASTPIN (-3050 2850) BN 6
J 0
(-3100 2860);
DISPLAY 0.617021 (-3100 2860);
PAINT PINK (-3100 2860);
FORCEPROP 2 LAST CDS_LIB mstr_standard
J 0
(-3100 2850);
DISPLAY 0.787234 (-3100 2850);
PAINT MONO (-3100 2850);
DISPLAY INVISIBLE (-3100 2850);
FORCEPROP 1 LAST BODY_TYPE PLUMBING
J 0
(-3100 2800);
DISPLAY 1.234043 (-3100 2800);
PAINT GREEN (-3100 2800);
DISPLAY INVISIBLE (-3100 2800);
FORCEPROP 1 LAST HDL_TAP TRUE
J 0
(-2775 2725);
DISPLAY 1.234043 (-2775 2725);
PAINT GREEN (-2775 2725);
DISPLAY INVISIBLE (-2775 2725);
FORCEPROP 1 LAST PATH I139
J 0
(-3100 2850);
DISPLAY 0.936170 (-3100 2850);
PAINT GREEN (-3100 2850);
DISPLAY INVISIBLE (-3100 2850);
FORCEADD TAP..6
R 2
(700 4550);
FORCEPROP 3 LASTPIN (650 4550) SIG_NAME M_E_DQS_DP<11>
J 0
(660 4560);
DISPLAY 0.659574 (660 4560);
PAINT MONO (660 4560);
DISPLAY INVISIBLE (660 4560);
FORCEPROP 1 LASTPIN (650 4550) BN 11
J 2
(700 4560);
DISPLAY 0.617021 (700 4560);
PAINT PINK (700 4560);
FORCEPROP 2 LAST CDS_LIB mstr_standard
J 0
(700 4550);
DISPLAY 0.787234 (700 4550);
PAINT MONO (700 4550);
DISPLAY INVISIBLE (700 4550);
FORCEPROP 1 LAST BODY_TYPE PLUMBING
J 2
(700 4500);
DISPLAY 1.234043 (700 4500);
PAINT GREEN (700 4500);
DISPLAY INVISIBLE (700 4500);
FORCEPROP 1 LAST HDL_TAP TRUE
J 2
(375 4425);
DISPLAY 1.234043 (375 4425);
PAINT GREEN (375 4425);
DISPLAY INVISIBLE (375 4425);
FORCEPROP 1 LAST PATH I14
J 2
(700 4550);
DISPLAY 0.936170 (700 4550);
PAINT GREEN (700 4550);
DISPLAY INVISIBLE (700 4550);
FORCEADD TAP..6
(-3100 2750);
FORCEPROP 3 LASTPIN (-3050 2750) SIG_NAME M_E_ECC<4>
J 0
(-3040 2760);
DISPLAY 0.659574 (-3040 2760);
PAINT MONO (-3040 2760);
DISPLAY INVISIBLE (-3040 2760);
FORCEPROP 1 LASTPIN (-3050 2750) BN 4
J 0
(-3100 2760);
DISPLAY 0.617021 (-3100 2760);
PAINT PINK (-3100 2760);
FORCEPROP 2 LAST CDS_LIB mstr_standard
J 0
(-3100 2750);
DISPLAY 0.787234 (-3100 2750);
PAINT MONO (-3100 2750);
DISPLAY INVISIBLE (-3100 2750);
FORCEPROP 1 LAST BODY_TYPE PLUMBING
J 0
(-3100 2700);
DISPLAY 1.234043 (-3100 2700);
PAINT GREEN (-3100 2700);
DISPLAY INVISIBLE (-3100 2700);
FORCEPROP 1 LAST HDL_TAP TRUE
J 0
(-2775 2625);
DISPLAY 1.234043 (-2775 2625);
PAINT GREEN (-2775 2625);
DISPLAY INVISIBLE (-2775 2625);
FORCEPROP 1 LAST PATH I140
J 0
(-3100 2750);
DISPLAY 0.936170 (-3100 2750);
PAINT GREEN (-3100 2750);
DISPLAY INVISIBLE (-3100 2750);
FORCEADD TAP..6
(-3100 2700);
FORCEPROP 3 LASTPIN (-3050 2700) SIG_NAME M_E_ECC<5>
J 0
(-3040 2710);
DISPLAY 0.659574 (-3040 2710);
PAINT MONO (-3040 2710);
DISPLAY INVISIBLE (-3040 2710);
FORCEPROP 1 LASTPIN (-3050 2700) BN 5
J 0
(-3100 2710);
DISPLAY 0.617021 (-3100 2710);
PAINT PINK (-3100 2710);
FORCEPROP 2 LAST CDS_LIB mstr_standard
J 0
(-3100 2700);
DISPLAY 0.787234 (-3100 2700);
PAINT MONO (-3100 2700);
DISPLAY INVISIBLE (-3100 2700);
FORCEPROP 1 LAST BODY_TYPE PLUMBING
J 0
(-3100 2650);
DISPLAY 1.234043 (-3100 2650);
PAINT GREEN (-3100 2650);
DISPLAY INVISIBLE (-3100 2650);
FORCEPROP 1 LAST HDL_TAP TRUE
J 0
(-2775 2575);
DISPLAY 1.234043 (-2775 2575);
PAINT GREEN (-2775 2575);
DISPLAY INVISIBLE (-2775 2575);
FORCEPROP 1 LAST PATH I141
J 0
(-3100 2700);
DISPLAY 0.936170 (-3100 2700);
PAINT GREEN (-3100 2700);
DISPLAY INVISIBLE (-3100 2700);
FORCEADD TAP..6
(-3100 2650);
FORCEPROP 3 LASTPIN (-3050 2650) SIG_NAME M_E_ECC<2>
J 0
(-3040 2660);
DISPLAY 0.659574 (-3040 2660);
PAINT MONO (-3040 2660);
DISPLAY INVISIBLE (-3040 2660);
FORCEPROP 1 LASTPIN (-3050 2650) BN 2
J 0
(-3100 2660);
DISPLAY 0.617021 (-3100 2660);
PAINT PINK (-3100 2660);
FORCEPROP 2 LAST CDS_LIB mstr_standard
J 0
(-3100 2650);
DISPLAY 0.787234 (-3100 2650);
PAINT MONO (-3100 2650);
DISPLAY INVISIBLE (-3100 2650);
FORCEPROP 1 LAST BODY_TYPE PLUMBING
J 0
(-3100 2600);
DISPLAY 1.234043 (-3100 2600);
PAINT GREEN (-3100 2600);
DISPLAY INVISIBLE (-3100 2600);
FORCEPROP 1 LAST HDL_TAP TRUE
J 0
(-2775 2525);
DISPLAY 1.234043 (-2775 2525);
PAINT GREEN (-2775 2525);
DISPLAY INVISIBLE (-2775 2525);
FORCEPROP 1 LAST PATH I142
J 0
(-3100 2650);
DISPLAY 0.936170 (-3100 2650);
PAINT GREEN (-3100 2650);
DISPLAY INVISIBLE (-3100 2650);
FORCEADD TAP..6
(-3100 2600);
FORCEPROP 3 LASTPIN (-3050 2600) SIG_NAME M_E_ECC<3>
J 0
(-3040 2610);
DISPLAY 0.659574 (-3040 2610);
PAINT MONO (-3040 2610);
DISPLAY INVISIBLE (-3040 2610);
FORCEPROP 1 LASTPIN (-3050 2600) BN 3
J 0
(-3100 2610);
DISPLAY 0.617021 (-3100 2610);
PAINT PINK (-3100 2610);
FORCEPROP 2 LAST CDS_LIB mstr_standard
J 0
(-3100 2600);
DISPLAY 0.787234 (-3100 2600);
PAINT MONO (-3100 2600);
DISPLAY INVISIBLE (-3100 2600);
FORCEPROP 1 LAST BODY_TYPE PLUMBING
J 0
(-3100 2550);
DISPLAY 1.234043 (-3100 2550);
PAINT GREEN (-3100 2550);
DISPLAY INVISIBLE (-3100 2550);
FORCEPROP 1 LAST HDL_TAP TRUE
J 0
(-2775 2475);
DISPLAY 1.234043 (-2775 2475);
PAINT GREEN (-2775 2475);
DISPLAY INVISIBLE (-2775 2475);
FORCEPROP 1 LAST PATH I143
J 0
(-3100 2600);
DISPLAY 0.936170 (-3100 2600);
PAINT GREEN (-3100 2600);
DISPLAY INVISIBLE (-3100 2600);
FORCEADD TAP..6
(-3100 2550);
FORCEPROP 3 LASTPIN (-3050 2550) SIG_NAME M_E_ECC<0>
J 0
(-3040 2560);
DISPLAY 0.659574 (-3040 2560);
PAINT MONO (-3040 2560);
DISPLAY INVISIBLE (-3040 2560);
FORCEPROP 1 LASTPIN (-3050 2550) BN 0
J 0
(-3100 2560);
DISPLAY 0.617021 (-3100 2560);
PAINT PINK (-3100 2560);
FORCEPROP 2 LAST CDS_LIB mstr_standard
J 0
(-3100 2550);
DISPLAY 0.787234 (-3100 2550);
PAINT MONO (-3100 2550);
DISPLAY INVISIBLE (-3100 2550);
FORCEPROP 1 LAST BODY_TYPE PLUMBING
J 0
(-3100 2500);
DISPLAY 1.234043 (-3100 2500);
PAINT GREEN (-3100 2500);
DISPLAY INVISIBLE (-3100 2500);
FORCEPROP 1 LAST HDL_TAP TRUE
J 0
(-2775 2425);
DISPLAY 1.234043 (-2775 2425);
PAINT GREEN (-2775 2425);
DISPLAY INVISIBLE (-2775 2425);
FORCEPROP 1 LAST PATH I144
J 0
(-3100 2550);
DISPLAY 0.936170 (-3100 2550);
PAINT GREEN (-3100 2550);
DISPLAY INVISIBLE (-3100 2550);
FORCEADD TAP..6
(-3100 2500);
FORCEPROP 3 LASTPIN (-3050 2500) SIG_NAME M_E_ECC<1>
J 0
(-3040 2510);
DISPLAY 0.659574 (-3040 2510);
PAINT MONO (-3040 2510);
DISPLAY INVISIBLE (-3040 2510);
FORCEPROP 1 LASTPIN (-3050 2500) BN 1
J 0
(-3100 2510);
DISPLAY 0.617021 (-3100 2510);
PAINT PINK (-3100 2510);
FORCEPROP 2 LAST CDS_LIB mstr_standard
J 0
(-3100 2500);
DISPLAY 0.787234 (-3100 2500);
PAINT MONO (-3100 2500);
DISPLAY INVISIBLE (-3100 2500);
FORCEPROP 1 LAST BODY_TYPE PLUMBING
J 0
(-3100 2450);
DISPLAY 1.234043 (-3100 2450);
PAINT GREEN (-3100 2450);
DISPLAY INVISIBLE (-3100 2450);
FORCEPROP 1 LAST HDL_TAP TRUE
J 0
(-2775 2375);
DISPLAY 1.234043 (-2775 2375);
PAINT GREEN (-2775 2375);
DISPLAY INVISIBLE (-2775 2375);
FORCEPROP 1 LAST PATH I145
J 0
(-3100 2500);
DISPLAY 0.936170 (-3100 2500);
PAINT GREEN (-3100 2500);
DISPLAY INVISIBLE (-3100 2500);
FORCEADD OFFPAGE..1
(-3900 2850);
FORCEPROP 2 LAST $XR1 52 
J 0
(-4271 2850);
DISPLAY 0.638298 (-4271 2850);
PAINT MONO (-4271 2850);
FORCEPROP 2 LAST $XR0 27 
J 0
(-4181 2850);
DISPLAY 0.638298 (-4181 2850);
PAINT MONO (-4181 2850);
FORCEPROP 2 LAST CDS_LIB mstr_standard
J 0
(-3900 2850);
DISPLAY 0.787234 (-3900 2850);
PAINT MONO (-3900 2850);
DISPLAY INVISIBLE (-3900 2850);
FORCEPROP 1 LAST OFFPAGE TRUE
J 0
(-3575 2725);
DISPLAY 0.936170 (-3575 2725);
PAINT GREEN (-3575 2725);
DISPLAY INVISIBLE (-3575 2725);
FORCEPROP 1 LAST COMMENT_BODY TRUE
J 0
(-3775 2750);
DISPLAY 0.936170 (-3775 2750);
PAINT GREEN (-3775 2750);
DISPLAY INVISIBLE (-3775 2750);
FORCEPROP 2 LAST PATH I146
J 0
(-3850 2925);
DISPLAY 0.787234 (-3850 2925);
PAINT MONO (-3850 2925);
DISPLAY INVISIBLE (-3850 2925);
FORCEADD OFFPAGE..1
(-3900 2200);
FORCEPROP 2 LAST $XR1 52 
J 0
(-4271 2200);
DISPLAY 0.638298 (-4271 2200);
PAINT MONO (-4271 2200);
FORCEPROP 2 LAST $XR0 27 
J 0
(-4181 2200);
DISPLAY 0.638298 (-4181 2200);
PAINT MONO (-4181 2200);
FORCEPROP 2 LAST CDS_LIB mstr_standard
J 0
(-3900 2200);
DISPLAY 0.787234 (-3900 2200);
PAINT MONO (-3900 2200);
DISPLAY INVISIBLE (-3900 2200);
FORCEPROP 1 LAST OFFPAGE TRUE
J 0
(-3575 2075);
DISPLAY 0.936170 (-3575 2075);
PAINT GREEN (-3575 2075);
DISPLAY INVISIBLE (-3575 2075);
FORCEPROP 1 LAST COMMENT_BODY TRUE
J 0
(-3775 2100);
DISPLAY 0.936170 (-3775 2100);
PAINT GREEN (-3775 2100);
DISPLAY INVISIBLE (-3775 2100);
FORCEPROP 2 LAST PATH I147
J 0
(-3850 2275);
DISPLAY 0.787234 (-3850 2275);
PAINT MONO (-3850 2275);
DISPLAY INVISIBLE (-3850 2275);
FORCEADD OFFPAGE..5
(-3925 2250);
FORCEPROP 2 LAST $XR1 27 
J 0
(-4269 2250);
DISPLAY 0.638298 (-4269 2250);
PAINT MONO (-4269 2250);
FORCEPROP 2 LAST $XR0 52 
J 0
(-4179 2250);
DISPLAY 0.638298 (-4179 2250);
PAINT MONO (-4179 2250);
FORCEPROP 2 LAST CDS_LIB mstr_standard
J 0
(-3925 2250);
DISPLAY 0.787234 (-3925 2250);
PAINT MONO (-3925 2250);
DISPLAY INVISIBLE (-3925 2250);
FORCEPROP 1 LAST OFFPAGE TRUE
J 0
(-3600 2125);
DISPLAY 1.404255 (-3600 2125);
PAINT GREEN (-3600 2125);
DISPLAY INVISIBLE (-3600 2125);
FORCEPROP 1 LAST COMMENT_BODY TRUE
J 0
(-3825 2175);
DISPLAY 1.404255 (-3825 2175);
PAINT GREEN (-3825 2175);
DISPLAY INVISIBLE (-3825 2175);
FORCEPROP 2 LAST PATH I148
J 0
(-3875 2325);
DISPLAY 0.787234 (-3875 2325);
PAINT MONO (-3875 2325);
DISPLAY INVISIBLE (-3875 2325);
FORCEADD OFFPAGE..1
(-3900 2800);
FORCEPROP 2 LAST $XR5 54 
J 0
(-4571 2800);
DISPLAY 0.638298 (-4571 2800);
PAINT MONO (-4571 2800);
FORCEPROP 2 LAST $XR4 53 
J 0
(-4481 2800);
DISPLAY 0.638298 (-4481 2800);
PAINT MONO (-4481 2800);
FORCEPROP 2 LAST $XR3 52 
J 0
(-4391 2800);
DISPLAY 0.638298 (-4391 2800);
PAINT MONO (-4391 2800);
FORCEPROP 2 LAST $XR2 50 
J 0
(-4301 2800);
DISPLAY 0.638298 (-4301 2800);
PAINT MONO (-4301 2800);
FORCEPROP 2 LAST $XR1 49 
J 0
(-4211 2800);
DISPLAY 0.638298 (-4211 2800);
PAINT MONO (-4211 2800);
FORCEPROP 2 LAST $XR0 21 
J 0
(-4121 2800);
DISPLAY 0.638298 (-4121 2800);
PAINT MONO (-4121 2800);
FORCEPROP 2 LAST CDS_LIB mstr_standard
J 0
(-3900 2800);
DISPLAY 0.787234 (-3900 2800);
PAINT MONO (-3900 2800);
DISPLAY INVISIBLE (-3900 2800);
FORCEPROP 1 LAST OFFPAGE TRUE
J 0
(-3575 2675);
DISPLAY 0.936170 (-3575 2675);
PAINT GREEN (-3575 2675);
DISPLAY INVISIBLE (-3575 2675);
FORCEPROP 1 LAST COMMENT_BODY TRUE
J 0
(-3775 2700);
DISPLAY 0.936170 (-3775 2700);
PAINT GREEN (-3775 2700);
DISPLAY INVISIBLE (-3775 2700);
FORCEPROP 2 LAST PATH I149
J 0
(-3850 2875);
DISPLAY 0.787234 (-3850 2875);
PAINT MONO (-3850 2875);
DISPLAY INVISIBLE (-3850 2875);
FORCEADD TAP..6
R 2
(700 4650);
FORCEPROP 3 LASTPIN (650 4650) SIG_NAME M_E_DQS_DP<12>
J 0
(660 4660);
DISPLAY 0.659574 (660 4660);
PAINT MONO (660 4660);
DISPLAY INVISIBLE (660 4660);
FORCEPROP 1 LASTPIN (650 4650) BN 12
J 2
(700 4660);
DISPLAY 0.617021 (700 4660);
PAINT PINK (700 4660);
FORCEPROP 2 LAST CDS_LIB mstr_standard
J 0
(700 4650);
DISPLAY 0.787234 (700 4650);
PAINT MONO (700 4650);
DISPLAY INVISIBLE (700 4650);
FORCEPROP 1 LAST BODY_TYPE PLUMBING
J 2
(700 4600);
DISPLAY 1.234043 (700 4600);
PAINT GREEN (700 4600);
DISPLAY INVISIBLE (700 4600);
FORCEPROP 1 LAST HDL_TAP TRUE
J 2
(375 4525);
DISPLAY 1.234043 (375 4525);
PAINT GREEN (375 4525);
DISPLAY INVISIBLE (375 4525);
FORCEPROP 1 LAST PATH I15
J 2
(700 4650);
DISPLAY 0.936170 (700 4650);
PAINT GREEN (700 4650);
DISPLAY INVISIBLE (700 4650);
FORCEADD OFFPAGE..6
(-3900 2900);
FORCEPROP 2 LAST $XR1 52 
J 0
(-4269 2900);
DISPLAY 0.638298 (-4269 2900);
PAINT MONO (-4269 2900);
FORCEPROP 2 LAST $XR0 27 
J 0
(-4179 2900);
DISPLAY 0.638298 (-4179 2900);
PAINT MONO (-4179 2900);
FORCEPROP 2 LAST CDS_LIB mstr_standard
J 0
(-3900 2900);
DISPLAY 0.787234 (-3900 2900);
PAINT MONO (-3900 2900);
DISPLAY INVISIBLE (-3900 2900);
FORCEPROP 1 LAST OFFPAGE TRUE
J 0
(-3575 2775);
DISPLAY 0.936170 (-3575 2775);
PAINT GREEN (-3575 2775);
DISPLAY INVISIBLE (-3575 2775);
FORCEPROP 1 LAST COMMENT_BODY TRUE
J 0
(-3800 2825);
DISPLAY 0.936170 (-3800 2825);
PAINT GREEN (-3800 2825);
DISPLAY INVISIBLE (-3800 2825);
FORCEPROP 2 LAST PATH I150
J 0
(-3850 2975);
DISPLAY 0.787234 (-3850 2975);
PAINT MONO (-3850 2975);
DISPLAY INVISIBLE (-3850 2975);
FORCEADD OFFPAGE..1
(-4800 1750);
FORCEPROP 2 LAST $XR1 52 
J 0
(-5141 1750);
DISPLAY 0.638298 (-5141 1750);
PAINT MONO (-5141 1750);
FORCEPROP 2 LAST $XR0 98 
J 0
(-5051 1750);
DISPLAY 0.638298 (-5051 1750);
PAINT MONO (-5051 1750);
FORCEPROP 2 LAST CDS_LIB mstr_standard
J 0
(-4800 1750);
DISPLAY 0.787234 (-4800 1750);
PAINT MONO (-4800 1750);
DISPLAY INVISIBLE (-4800 1750);
FORCEPROP 1 LAST OFFPAGE TRUE
J 0
(-4475 1625);
DISPLAY 0.936170 (-4475 1625);
PAINT GREEN (-4475 1625);
DISPLAY INVISIBLE (-4475 1625);
FORCEPROP 1 LAST COMMENT_BODY TRUE
J 0
(-4675 1650);
DISPLAY 0.936170 (-4675 1650);
PAINT GREEN (-4675 1650);
DISPLAY INVISIBLE (-4675 1650);
FORCEPROP 2 LAST PATH I151
J 0
(-4750 1825);
DISPLAY 0.787234 (-4750 1825);
PAINT MONO (-4750 1825);
DISPLAY INVISIBLE (-4750 1825);
FORCEADD TAP..6
(-3500 3600);
FORCEPROP 3 LASTPIN (-3450 3600) SIG_NAME M_E_CLK_DP<0>
J 0
(-3440 3610);
DISPLAY 0.659574 (-3440 3610);
PAINT MONO (-3440 3610);
DISPLAY INVISIBLE (-3440 3610);
FORCEPROP 1 LASTPIN (-3450 3600) BN 0
J 0
(-3500 3610);
DISPLAY 0.617021 (-3500 3610);
PAINT PINK (-3500 3610);
FORCEPROP 2 LAST CDS_LIB mstr_standard
J 0
(-3500 3600);
DISPLAY 0.787234 (-3500 3600);
PAINT MONO (-3500 3600);
DISPLAY INVISIBLE (-3500 3600);
FORCEPROP 1 LAST BODY_TYPE PLUMBING
J 0
(-3500 3550);
DISPLAY 1.234043 (-3500 3550);
PAINT GREEN (-3500 3550);
DISPLAY INVISIBLE (-3500 3550);
FORCEPROP 1 LAST HDL_TAP TRUE
J 0
(-3175 3475);
DISPLAY 1.234043 (-3175 3475);
PAINT GREEN (-3175 3475);
DISPLAY INVISIBLE (-3175 3475);
FORCEPROP 1 LAST PATH I152
J 0
(-3500 3600);
DISPLAY 0.936170 (-3500 3600);
PAINT GREEN (-3500 3600);
DISPLAY INVISIBLE (-3500 3600);
FORCEADD TAP..6
(-3650 3550);
FORCEPROP 3 LASTPIN (-3600 3550) SIG_NAME M_E_CLK_DN<0>
J 0
(-3590 3560);
DISPLAY 0.659574 (-3590 3560);
PAINT MONO (-3590 3560);
DISPLAY INVISIBLE (-3590 3560);
FORCEPROP 1 LASTPIN (-3600 3550) BN 0
J 0
(-3650 3560);
DISPLAY 0.617021 (-3650 3560);
PAINT PINK (-3650 3560);
FORCEPROP 2 LAST CDS_LIB mstr_standard
J 0
(-3650 3550);
DISPLAY 0.787234 (-3650 3550);
PAINT MONO (-3650 3550);
DISPLAY INVISIBLE (-3650 3550);
FORCEPROP 1 LAST BODY_TYPE PLUMBING
J 0
(-3650 3500);
DISPLAY 1.234043 (-3650 3500);
PAINT GREEN (-3650 3500);
DISPLAY INVISIBLE (-3650 3500);
FORCEPROP 1 LAST HDL_TAP TRUE
J 0
(-3325 3425);
DISPLAY 1.234043 (-3325 3425);
PAINT GREEN (-3325 3425);
DISPLAY INVISIBLE (-3325 3425);
FORCEPROP 1 LAST PATH I153
J 0
(-3650 3550);
DISPLAY 0.936170 (-3650 3550);
PAINT GREEN (-3650 3550);
DISPLAY INVISIBLE (-3650 3550);
FORCEADD OFFPAGE..1
(-4200 3750);
FORCEPROP 2 LAST $XR1 52 
J 0
(-4541 3750);
DISPLAY 0.638298 (-4541 3750);
PAINT MONO (-4541 3750);
FORCEPROP 2 LAST $XR0 27 
J 0
(-4451 3750);
DISPLAY 0.638298 (-4451 3750);
PAINT MONO (-4451 3750);
FORCEPROP 2 LAST CDS_LIB mstr_standard
J 0
(-4200 3750);
DISPLAY 0.787234 (-4200 3750);
PAINT MONO (-4200 3750);
DISPLAY INVISIBLE (-4200 3750);
FORCEPROP 1 LAST OFFPAGE TRUE
J 0
(-3875 3625);
DISPLAY 0.936170 (-3875 3625);
PAINT GREEN (-3875 3625);
DISPLAY INVISIBLE (-3875 3625);
FORCEPROP 1 LAST COMMENT_BODY TRUE
J 0
(-4075 3650);
DISPLAY 0.936170 (-4075 3650);
PAINT GREEN (-4075 3650);
DISPLAY INVISIBLE (-4075 3650);
FORCEPROP 2 LAST PATH I154
J 0
(-4150 3825);
DISPLAY 0.787234 (-4150 3825);
PAINT MONO (-4150 3825);
DISPLAY INVISIBLE (-4150 3825);
FORCEADD OFFPAGE..1
(-4200 3800);
FORCEPROP 2 LAST $XR1 52 
J 0
(-4541 3800);
DISPLAY 0.638298 (-4541 3800);
PAINT MONO (-4541 3800);
FORCEPROP 2 LAST $XR0 27 
J 0
(-4451 3800);
DISPLAY 0.638298 (-4451 3800);
PAINT MONO (-4451 3800);
FORCEPROP 2 LAST CDS_LIB mstr_standard
J 0
(-4200 3800);
DISPLAY 0.787234 (-4200 3800);
PAINT MONO (-4200 3800);
DISPLAY INVISIBLE (-4200 3800);
FORCEPROP 1 LAST OFFPAGE TRUE
J 0
(-3875 3675);
DISPLAY 0.936170 (-3875 3675);
PAINT GREEN (-3875 3675);
DISPLAY INVISIBLE (-3875 3675);
FORCEPROP 1 LAST COMMENT_BODY TRUE
J 0
(-4075 3700);
DISPLAY 0.936170 (-4075 3700);
PAINT GREEN (-4075 3700);
DISPLAY INVISIBLE (-4075 3700);
FORCEPROP 2 LAST PATH I155
J 0
(-4150 3875);
DISPLAY 0.787234 (-4150 3875);
PAINT MONO (-4150 3875);
DISPLAY INVISIBLE (-4150 3875);
FORCEADD TAP..6
(-3100 3400);
FORCEPROP 3 LASTPIN (-3050 3400) SIG_NAME M_E_CS_N<3>
J 0
(-3040 3410);
DISPLAY 0.659574 (-3040 3410);
PAINT MONO (-3040 3410);
DISPLAY INVISIBLE (-3040 3410);
FORCEPROP 1 LASTPIN (-3050 3400) BN 3
J 0
(-3100 3410);
DISPLAY 0.617021 (-3100 3410);
PAINT PINK (-3100 3410);
FORCEPROP 2 LAST CDS_LIB mstr_standard
J 0
(-3100 3400);
DISPLAY 0.787234 (-3100 3400);
PAINT MONO (-3100 3400);
DISPLAY INVISIBLE (-3100 3400);
FORCEPROP 1 LAST BODY_TYPE PLUMBING
J 0
(-3100 3350);
DISPLAY 1.234043 (-3100 3350);
PAINT GREEN (-3100 3350);
DISPLAY INVISIBLE (-3100 3350);
FORCEPROP 1 LAST HDL_TAP TRUE
J 0
(-2775 3275);
DISPLAY 1.234043 (-2775 3275);
PAINT GREEN (-2775 3275);
DISPLAY INVISIBLE (-2775 3275);
FORCEPROP 1 LAST PATH I156
J 0
(-3100 3400);
DISPLAY 0.936170 (-3100 3400);
PAINT GREEN (-3100 3400);
DISPLAY INVISIBLE (-3100 3400);
FORCEADD TAP..6
(-3100 3350);
FORCEPROP 3 LASTPIN (-3050 3350) SIG_NAME M_E_CS_N<2>
J 0
(-3040 3360);
DISPLAY 0.659574 (-3040 3360);
PAINT MONO (-3040 3360);
DISPLAY INVISIBLE (-3040 3360);
FORCEPROP 1 LASTPIN (-3050 3350) BN 2
J 0
(-3100 3360);
DISPLAY 0.617021 (-3100 3360);
PAINT PINK (-3100 3360);
FORCEPROP 2 LAST CDS_LIB mstr_standard
J 0
(-3100 3350);
DISPLAY 0.787234 (-3100 3350);
PAINT MONO (-3100 3350);
DISPLAY INVISIBLE (-3100 3350);
FORCEPROP 1 LAST BODY_TYPE PLUMBING
J 0
(-3100 3300);
DISPLAY 1.234043 (-3100 3300);
PAINT GREEN (-3100 3300);
DISPLAY INVISIBLE (-3100 3300);
FORCEPROP 1 LAST HDL_TAP TRUE
J 0
(-2775 3225);
DISPLAY 1.234043 (-2775 3225);
PAINT GREEN (-2775 3225);
DISPLAY INVISIBLE (-2775 3225);
FORCEPROP 1 LAST PATH I157
J 0
(-3100 3350);
DISPLAY 0.936170 (-3100 3350);
PAINT GREEN (-3100 3350);
DISPLAY INVISIBLE (-3100 3350);
FORCEADD TAP..6
(-3100 3300);
FORCEPROP 3 LASTPIN (-3050 3300) SIG_NAME M_E_CS_N<1>
J 0
(-3040 3310);
DISPLAY 0.659574 (-3040 3310);
PAINT MONO (-3040 3310);
DISPLAY INVISIBLE (-3040 3310);
FORCEPROP 1 LASTPIN (-3050 3300) BN 1
J 0
(-3100 3310);
DISPLAY 0.617021 (-3100 3310);
PAINT PINK (-3100 3310);
FORCEPROP 2 LAST CDS_LIB mstr_standard
J 0
(-3100 3300);
DISPLAY 0.787234 (-3100 3300);
PAINT MONO (-3100 3300);
DISPLAY INVISIBLE (-3100 3300);
FORCEPROP 1 LAST BODY_TYPE PLUMBING
J 0
(-3100 3250);
DISPLAY 1.234043 (-3100 3250);
PAINT GREEN (-3100 3250);
DISPLAY INVISIBLE (-3100 3250);
FORCEPROP 1 LAST HDL_TAP TRUE
J 0
(-2775 3175);
DISPLAY 1.234043 (-2775 3175);
PAINT GREEN (-2775 3175);
DISPLAY INVISIBLE (-2775 3175);
FORCEPROP 1 LAST PATH I158
J 0
(-3100 3300);
DISPLAY 0.936170 (-3100 3300);
PAINT GREEN (-3100 3300);
DISPLAY INVISIBLE (-3100 3300);
FORCEADD TAP..6
(-3100 3250);
FORCEPROP 3 LASTPIN (-3050 3250) SIG_NAME M_E_CS_N<0>
J 0
(-3040 3260);
DISPLAY 0.659574 (-3040 3260);
PAINT MONO (-3040 3260);
DISPLAY INVISIBLE (-3040 3260);
FORCEPROP 1 LASTPIN (-3050 3250) BN 0
J 0
(-3100 3260);
DISPLAY 0.617021 (-3100 3260);
PAINT PINK (-3100 3260);
FORCEPROP 2 LAST CDS_LIB mstr_standard
J 0
(-3100 3250);
DISPLAY 0.787234 (-3100 3250);
PAINT MONO (-3100 3250);
DISPLAY INVISIBLE (-3100 3250);
FORCEPROP 1 LAST BODY_TYPE PLUMBING
J 0
(-3100 3200);
DISPLAY 1.234043 (-3100 3200);
PAINT GREEN (-3100 3200);
DISPLAY INVISIBLE (-3100 3200);
FORCEPROP 1 LAST HDL_TAP TRUE
J 0
(-2775 3125);
DISPLAY 1.234043 (-2775 3125);
PAINT GREEN (-2775 3125);
DISPLAY INVISIBLE (-2775 3125);
FORCEPROP 1 LAST PATH I159
J 0
(-3100 3250);
DISPLAY 0.936170 (-3100 3250);
PAINT GREEN (-3100 3250);
DISPLAY INVISIBLE (-3100 3250);
FORCEADD PVDDQ_DEF..1
(-1225 2600);
FORCEPROP 3 LASTPIN (-1225 2550) SIG_NAME PVDDQ_DEF\g
J 0
(-1215 2560);
DISPLAY 0.659574 (-1215 2560);
PAINT MONO (-1215 2560);
DISPLAY INVISIBLE (-1215 2560);
FORCEPROP 1 LAST VOLTAGE 1.2V
J 0
(-1270 2557);
DISPLAY 0.340426 (-1270 2557);
PAINT SKYBLUE (-1270 2557);
DISPLAY INVISIBLE (-1270 2557);
FORCEPROP 2 LAST BOM_COST MEM
J 0
(-1225 2605);
PAINT ORANGE (-1225 2605);
DISPLAY INVISIBLE (-1225 2605);
FORCEPROP 2 LAST CDS_LIB mstr_symbols
J 0
(-1225 2600);
PAINT ORANGE (-1225 2600);
DISPLAY INVISIBLE (-1225 2600);
FORCEPROP 1 LAST BODY_TYPE PLUMBING
J 0
(-1270 2557);
DISPLAY 0.340426 (-1270 2557);
PAINT GREEN (-1270 2557);
DISPLAY INVISIBLE (-1270 2557);
FORCEPROP 1 LAST PATH I16
J 0
(-1175 2625);
DISPLAY 0.872340 (-1175 2625);
PAINT AQUA (-1175 2625);
DISPLAY INVISIBLE (-1175 2625);
FORCEPROP 2 LAST ROOM DDR4_CH_B
J 0
(-1225 2700);
DISPLAY 0.787234 (-1225 2700);
PAINT ORANGE (-1225 2700);
DISPLAY INVISIBLE (-1225 2700);
FORCEPROP 1 LAST HDL_POWER PVDDQ_DEF
J 1
(-1225 2650);
DISPLAY 0.872340 (-1225 2650);
PAINT GREEN (-1225 2650);
DISPLAY INVISIBLE (-1225 2650);
FORCEADD TAP..6
(-3150 3150);
FORCEPROP 3 LASTPIN (-3100 3150) SIG_NAME M_E_CKE<1>
J 0
(-3090 3160);
DISPLAY 0.659574 (-3090 3160);
PAINT MONO (-3090 3160);
DISPLAY INVISIBLE (-3090 3160);
FORCEPROP 1 LASTPIN (-3100 3150) BN 1
J 0
(-3150 3160);
DISPLAY 0.617021 (-3150 3160);
PAINT PINK (-3150 3160);
FORCEPROP 2 LAST CDS_LIB mstr_standard
J 0
(-3150 3150);
DISPLAY 0.787234 (-3150 3150);
PAINT MONO (-3150 3150);
DISPLAY INVISIBLE (-3150 3150);
FORCEPROP 1 LAST BODY_TYPE PLUMBING
J 0
(-3150 3100);
DISPLAY 1.234043 (-3150 3100);
PAINT GREEN (-3150 3100);
DISPLAY INVISIBLE (-3150 3100);
FORCEPROP 1 LAST HDL_TAP TRUE
J 0
(-2825 3025);
DISPLAY 1.234043 (-2825 3025);
PAINT GREEN (-2825 3025);
DISPLAY INVISIBLE (-2825 3025);
FORCEPROP 1 LAST PATH I160
J 0
(-3150 3150);
DISPLAY 0.936170 (-3150 3150);
PAINT GREEN (-3150 3150);
DISPLAY INVISIBLE (-3150 3150);
FORCEADD OFFPAGE..1
(-3900 3450);
FORCEPROP 2 LAST $XR1 52 
J 0
(-4211 3450);
DISPLAY 0.638298 (-4211 3450);
PAINT MONO (-4211 3450);
FORCEPROP 2 LAST $XR0 27 
J 0
(-4121 3450);
DISPLAY 0.638298 (-4121 3450);
PAINT MONO (-4121 3450);
FORCEPROP 2 LAST CDS_LIB mstr_standard
J 0
(-3900 3450);
DISPLAY 0.787234 (-3900 3450);
PAINT MONO (-3900 3450);
DISPLAY INVISIBLE (-3900 3450);
FORCEPROP 1 LAST OFFPAGE TRUE
J 0
(-3575 3325);
DISPLAY 0.936170 (-3575 3325);
PAINT GREEN (-3575 3325);
DISPLAY INVISIBLE (-3575 3325);
FORCEPROP 1 LAST COMMENT_BODY TRUE
J 0
(-3775 3350);
DISPLAY 0.936170 (-3775 3350);
PAINT GREEN (-3775 3350);
DISPLAY INVISIBLE (-3775 3350);
FORCEPROP 2 LAST PATH I161
J 0
(-3850 3525);
DISPLAY 0.787234 (-3850 3525);
PAINT MONO (-3850 3525);
DISPLAY INVISIBLE (-3850 3525);
FORCEADD OFFPAGE..1
(-3900 3200);
FORCEPROP 2 LAST $XR1 52 
J 0
(-4211 3200);
DISPLAY 0.638298 (-4211 3200);
PAINT MONO (-4211 3200);
FORCEPROP 2 LAST $XR0 27 
J 0
(-4121 3200);
DISPLAY 0.638298 (-4121 3200);
PAINT MONO (-4121 3200);
FORCEPROP 2 LAST CDS_LIB mstr_standard
J 0
(-3900 3200);
DISPLAY 0.787234 (-3900 3200);
PAINT MONO (-3900 3200);
DISPLAY INVISIBLE (-3900 3200);
FORCEPROP 1 LAST OFFPAGE TRUE
J 0
(-3575 3075);
DISPLAY 0.936170 (-3575 3075);
PAINT GREEN (-3575 3075);
DISPLAY INVISIBLE (-3575 3075);
FORCEPROP 1 LAST COMMENT_BODY TRUE
J 0
(-3775 3100);
DISPLAY 0.936170 (-3775 3100);
PAINT GREEN (-3775 3100);
DISPLAY INVISIBLE (-3775 3100);
FORCEPROP 2 LAST PATH I162
J 0
(-3850 3275);
DISPLAY 0.787234 (-3850 3275);
PAINT MONO (-3850 3275);
DISPLAY INVISIBLE (-3850 3275);
FORCEADD TAP..6
(-3150 3100);
FORCEPROP 3 LASTPIN (-3100 3100) SIG_NAME M_E_CKE<0>
J 0
(-3090 3110);
DISPLAY 0.659574 (-3090 3110);
PAINT MONO (-3090 3110);
DISPLAY INVISIBLE (-3090 3110);
FORCEPROP 1 LASTPIN (-3100 3100) BN 0
J 0
(-3150 3110);
DISPLAY 0.617021 (-3150 3110);
PAINT PINK (-3150 3110);
FORCEPROP 2 LAST CDS_LIB mstr_standard
J 0
(-3150 3100);
DISPLAY 0.787234 (-3150 3100);
PAINT MONO (-3150 3100);
DISPLAY INVISIBLE (-3150 3100);
FORCEPROP 1 LAST BODY_TYPE PLUMBING
J 0
(-3150 3050);
DISPLAY 1.234043 (-3150 3050);
PAINT GREEN (-3150 3050);
DISPLAY INVISIBLE (-3150 3050);
FORCEPROP 1 LAST HDL_TAP TRUE
J 0
(-2825 2975);
DISPLAY 1.234043 (-2825 2975);
PAINT GREEN (-2825 2975);
DISPLAY INVISIBLE (-2825 2975);
FORCEPROP 1 LAST PATH I163
J 0
(-3150 3100);
DISPLAY 0.936170 (-3150 3100);
PAINT GREEN (-3150 3100);
DISPLAY INVISIBLE (-3150 3100);
FORCEADD TAP..6
(-3100 3000);
FORCEPROP 3 LASTPIN (-3050 3000) SIG_NAME M_E_ODT<1>
J 0
(-3040 3010);
DISPLAY 0.659574 (-3040 3010);
PAINT MONO (-3040 3010);
DISPLAY INVISIBLE (-3040 3010);
FORCEPROP 1 LASTPIN (-3050 3000) BN 1
J 0
(-3100 3010);
DISPLAY 0.617021 (-3100 3010);
PAINT PINK (-3100 3010);
FORCEPROP 2 LAST CDS_LIB mstr_standard
J 0
(-3100 3000);
DISPLAY 0.787234 (-3100 3000);
PAINT MONO (-3100 3000);
DISPLAY INVISIBLE (-3100 3000);
FORCEPROP 1 LAST BODY_TYPE PLUMBING
J 0
(-3100 2950);
DISPLAY 1.234043 (-3100 2950);
PAINT GREEN (-3100 2950);
DISPLAY INVISIBLE (-3100 2950);
FORCEPROP 1 LAST HDL_TAP TRUE
J 0
(-2775 2875);
DISPLAY 1.234043 (-2775 2875);
PAINT GREEN (-2775 2875);
DISPLAY INVISIBLE (-2775 2875);
FORCEPROP 1 LAST PATH I164
J 0
(-3100 3000);
DISPLAY 0.936170 (-3100 3000);
PAINT GREEN (-3100 3000);
DISPLAY INVISIBLE (-3100 3000);
FORCEADD OFFPAGE..1
(-3900 3050);
FORCEPROP 2 LAST $XR1 52 
J 0
(-4211 3050);
DISPLAY 0.638298 (-4211 3050);
PAINT MONO (-4211 3050);
FORCEPROP 2 LAST $XR0 27 
J 0
(-4121 3050);
DISPLAY 0.638298 (-4121 3050);
PAINT MONO (-4121 3050);
FORCEPROP 2 LAST CDS_LIB mstr_standard
J 0
(-3900 3050);
DISPLAY 0.787234 (-3900 3050);
PAINT MONO (-3900 3050);
DISPLAY INVISIBLE (-3900 3050);
FORCEPROP 1 LAST OFFPAGE TRUE
J 0
(-3575 2925);
DISPLAY 0.936170 (-3575 2925);
PAINT GREEN (-3575 2925);
DISPLAY INVISIBLE (-3575 2925);
FORCEPROP 1 LAST COMMENT_BODY TRUE
J 0
(-3775 2950);
DISPLAY 0.936170 (-3775 2950);
PAINT GREEN (-3775 2950);
DISPLAY INVISIBLE (-3775 2950);
FORCEPROP 2 LAST PATH I165
J 0
(-3850 3125);
DISPLAY 0.787234 (-3850 3125);
PAINT MONO (-3850 3125);
DISPLAY INVISIBLE (-3850 3125);
FORCEADD TAP..6
(-3100 2950);
FORCEPROP 3 LASTPIN (-3050 2950) SIG_NAME M_E_ODT<0>
J 0
(-3040 2960);
DISPLAY 0.659574 (-3040 2960);
PAINT MONO (-3040 2960);
DISPLAY INVISIBLE (-3040 2960);
FORCEPROP 1 LASTPIN (-3050 2950) BN 0
J 0
(-3100 2960);
DISPLAY 0.617021 (-3100 2960);
PAINT PINK (-3100 2960);
FORCEPROP 2 LAST CDS_LIB mstr_standard
J 0
(-3100 2950);
DISPLAY 0.787234 (-3100 2950);
PAINT MONO (-3100 2950);
DISPLAY INVISIBLE (-3100 2950);
FORCEPROP 1 LAST BODY_TYPE PLUMBING
J 0
(-3100 2900);
DISPLAY 1.234043 (-3100 2900);
PAINT GREEN (-3100 2900);
DISPLAY INVISIBLE (-3100 2900);
FORCEPROP 1 LAST HDL_TAP TRUE
J 0
(-2775 2825);
DISPLAY 1.234043 (-2775 2825);
PAINT GREEN (-2775 2825);
DISPLAY INVISIBLE (-2775 2825);
FORCEPROP 1 LAST PATH I166
J 0
(-3100 2950);
DISPLAY 0.936170 (-3100 2950);
PAINT GREEN (-3100 2950);
DISPLAY INVISIBLE (-3100 2950);
FORCEADD SCONN288_H44441004..4
(-150 2050);
FORCEPROP 1 LAST LOCATION J4A2
J 0
(-600 3150);
DISPLAY 0.617021 (-600 3150);
PAINT AQUA (-600 3150);
FORCEPROP 1 LAST PART_NUMBER H44441-004
J 0
(-600 1000);
DISPLAY 0.617021 (-600 1000);
PAINT BLUE (-600 1000);
FORCEPROP 1 LAST MATERIAL SCONN
J 0
(-600 3100);
DISPLAY 0.617021 (-600 3100);
PAINT SKYBLUE (-600 3100);
FORCEPROP 2 LASTPIN (-650 2600) $PN 77
J 2
(-660 2610);
DISPLAY 0.617021 (-660 2610);
PAINT ORANGE (-660 2610);
FORCEPROP 2 LASTPIN (-650 2550) $PN 221
J 2
(-660 2560);
DISPLAY 0.617021 (-660 2560);
PAINT ORANGE (-660 2560);
FORCEPROP 2 LASTPIN (-650 2900) $PN 142
J 2
(-660 2910);
DISPLAY 0.617021 (-660 2910);
PAINT ORANGE (-660 2910);
FORCEPROP 2 LASTPIN (-650 2850) $PN 143
J 2
(-660 2860);
DISPLAY 0.617021 (-660 2860);
PAINT ORANGE (-660 2860);
FORCEPROP 2 LASTPIN (-650 2800) $PN 288
J 2
(-660 2810);
DISPLAY 0.617021 (-660 2810);
PAINT ORANGE (-660 2810);
FORCEPROP 2 LASTPIN (-650 2750) $PN 286
J 2
(-660 2760);
DISPLAY 0.617021 (-660 2760);
PAINT ORANGE (-660 2760);
FORCEPROP 2 LASTPIN (-650 2700) $PN 287
J 2
(-660 2710);
DISPLAY 0.617021 (-660 2710);
PAINT ORANGE (-660 2710);
FORCEPROP 2 LASTPIN (-650 2450) $PN 59
J 2
(-660 2460);
DISPLAY 0.617021 (-660 2460);
PAINT ORANGE (-660 2460);
FORCEPROP 2 LASTPIN (-650 2400) $PN 61
J 2
(-660 2410);
DISPLAY 0.617021 (-660 2410);
PAINT ORANGE (-660 2410);
FORCEPROP 2 LASTPIN (-650 2350) $PN 64
J 2
(-660 2360);
DISPLAY 0.617021 (-660 2360);
PAINT ORANGE (-660 2360);
FORCEPROP 2 LASTPIN (-650 2300) $PN 67
J 2
(-660 2310);
DISPLAY 0.617021 (-660 2310);
PAINT ORANGE (-660 2310);
FORCEPROP 2 LASTPIN (-650 2250) $PN 70
J 2
(-660 2260);
DISPLAY 0.617021 (-660 2260);
PAINT ORANGE (-660 2260);
FORCEPROP 2 LASTPIN (-650 2200) $PN 73
J 2
(-660 2210);
DISPLAY 0.617021 (-660 2210);
PAINT ORANGE (-660 2210);
FORCEPROP 2 LASTPIN (-650 2150) $PN 76
J 2
(-660 2160);
DISPLAY 0.617021 (-660 2160);
PAINT ORANGE (-660 2160);
FORCEPROP 2 LASTPIN (-650 2100) $PN 80
J 2
(-660 2110);
DISPLAY 0.617021 (-660 2110);
PAINT ORANGE (-660 2110);
FORCEPROP 2 LASTPIN (-650 2050) $PN 83
J 2
(-660 2060);
DISPLAY 0.617021 (-660 2060);
PAINT ORANGE (-660 2060);
FORCEPROP 2 LASTPIN (-650 2000) $PN 85
J 2
(-660 2010);
DISPLAY 0.617021 (-660 2010);
PAINT ORANGE (-660 2010);
FORCEPROP 2 LASTPIN (-650 1950) $PN 88
J 2
(-660 1960);
DISPLAY 0.617021 (-660 1960);
PAINT ORANGE (-660 1960);
FORCEPROP 2 LASTPIN (-650 1900) $PN 90
J 2
(-660 1910);
DISPLAY 0.617021 (-660 1910);
PAINT ORANGE (-660 1910);
FORCEPROP 2 LASTPIN (-650 1850) $PN 92
J 2
(-660 1860);
DISPLAY 0.617021 (-660 1860);
PAINT ORANGE (-660 1860);
FORCEPROP 2 LASTPIN (-650 1800) $PN 204
J 2
(-660 1810);
DISPLAY 0.617021 (-660 1810);
PAINT ORANGE (-660 1810);
FORCEPROP 2 LASTPIN (-650 1750) $PN 206
J 2
(-660 1760);
DISPLAY 0.617021 (-660 1760);
PAINT ORANGE (-660 1760);
FORCEPROP 2 LASTPIN (-650 1700) $PN 209
J 2
(-660 1710);
DISPLAY 0.617021 (-660 1710);
PAINT ORANGE (-660 1710);
FORCEPROP 2 LASTPIN (-650 1650) $PN 212
J 2
(-660 1660);
DISPLAY 0.617021 (-660 1660);
PAINT ORANGE (-660 1660);
FORCEPROP 2 LASTPIN (-650 1600) $PN 215
J 2
(-660 1610);
DISPLAY 0.617021 (-660 1610);
PAINT ORANGE (-660 1610);
FORCEPROP 2 LASTPIN (-650 1550) $PN 217
J 2
(-660 1560);
DISPLAY 0.617021 (-660 1560);
PAINT ORANGE (-660 1560);
FORCEPROP 2 LASTPIN (-650 1500) $PN 220
J 2
(-660 1510);
DISPLAY 0.617021 (-660 1510);
PAINT ORANGE (-660 1510);
FORCEPROP 2 LASTPIN (-650 1450) $PN 223
J 2
(-660 1460);
DISPLAY 0.617021 (-660 1460);
PAINT ORANGE (-660 1460);
FORCEPROP 2 LASTPIN (-650 1400) $PN 226
J 2
(-660 1410);
DISPLAY 0.617021 (-660 1410);
PAINT ORANGE (-660 1410);
FORCEPROP 2 LASTPIN (-650 1350) $PN 229
J 2
(-660 1360);
DISPLAY 0.617021 (-660 1360);
PAINT ORANGE (-660 1360);
FORCEPROP 2 LASTPIN (-650 1300) $PN 231
J 2
(-660 1310);
DISPLAY 0.617021 (-660 1310);
PAINT ORANGE (-660 1310);
FORCEPROP 2 LASTPIN (-650 1250) $PN 233
J 2
(-660 1260);
DISPLAY 0.617021 (-660 1260);
PAINT ORANGE (-660 1260);
FORCEPROP 2 LASTPIN (-650 1200) $PN 236
J 2
(-660 1210);
DISPLAY 0.617021 (-660 1210);
PAINT ORANGE (-660 1210);
FORCEPROP 2 LASTPIN (350 2900) $PN 1
J 0
(360 2910);
DISPLAY 0.617021 (360 2910);
PAINT ORANGE (360 2910);
FORCEPROP 2 LASTPIN (350 2850) $PN 145
J 0
(360 2860);
DISPLAY 0.617021 (360 2860);
PAINT ORANGE (360 2860);
FORCEPROP 1 LAST PACK_TYPE PIP
J 0
(-600 3200);
PAINT SKYBLUE (-600 3200);
DISPLAY INVISIBLE (-600 3200);
FORCEPROP 2 LAST BOM_COST MEM
J 0
(-150 2050);
PAINT ORANGE (-150 2050);
DISPLAY INVISIBLE (-150 2050);
FORCEPROP 2 LAST CDS_LIB mstr_sconn
J 0
(-150 2050);
PAINT ORANGE (-150 2050);
DISPLAY INVISIBLE (-150 2050);
FORCEPROP 2 LAST SEC_TYPE PIP
J 0
(-600 3200);
DISPLAY 1.021277 (-600 3200);
PAINT ORANGE (-600 3200);
DISPLAY INVISIBLE (-600 3200);
FORCEPROP 2 LAST SEC 4
J 0
(-600 3200);
DISPLAY 0.680851 (-600 3200);
PAINT MONO (-600 3200);
DISPLAY INVISIBLE (-600 3200);
FORCEPROP 2 LAST CDS_LOCATION J4A2
J 0
(-600 3150);
DISPLAY 0.617021 (-600 3150);
PAINT AQUA (-600 3150);
DISPLAY INVISIBLE (-600 3150);
FORCEPROP 1 LAST PATH I167
J 0
(-150 3100);
PAINT GREEN (-150 3100);
DISPLAY INVISIBLE (-150 3100);
FORCEPROP 2 LAST ROOM DDR4_CH_E
J 0
(-150 2050);
PAINT ORANGE (-150 2050);
DISPLAY INVISIBLE (-150 2050);
FORCEADD GND..1
R 2
(2500 1200);
FORCEPROP 3 LASTPIN (2500 1250) SIG_NAME GND\g
J 0
(2510 1260);
DISPLAY 0.659574 (2510 1260);
PAINT MONO (2510 1260);
DISPLAY INVISIBLE (2510 1260);
FORCEPROP 1 LAST VOLTAGE 0
J 0
(2500 1200);
PAINT SKYBLUE (2500 1200);
DISPLAY INVISIBLE (2500 1200);
FORCEPROP 1 LAST SIZE 1B
J 2
(2425 1150);
DISPLAY 1.170213 (2425 1150);
PAINT GREEN (2425 1150);
DISPLAY INVISIBLE (2425 1150);
FORCEPROP 2 LAST CDS_LIB mstr_symbols
J 0
(2500 1200);
DISPLAY 0.787234 (2500 1200);
PAINT MONO (2500 1200);
DISPLAY INVISIBLE (2500 1200);
FORCEPROP 2 LAST BOM_COST MEM
J 0
(2500 1205);
PAINT ORANGE (2500 1205);
DISPLAY INVISIBLE (2500 1205);
FORCEPROP 1 LAST BODY_TYPE PLUMBING
J 2
(2545 1157);
DISPLAY 0.340426 (2545 1157);
PAINT GREEN (2545 1157);
DISPLAY INVISIBLE (2545 1157);
FORCEPROP 1 LAST PATH I168
J 2
(2425 1200);
DISPLAY 1.404255 (2425 1200);
PAINT GREEN (2425 1200);
DISPLAY INVISIBLE (2425 1200);
FORCEPROP 2 LAST ROOM DDR4_CH_B
J 0
(2500 1205);
PAINT ORANGE (2500 1205);
DISPLAY INVISIBLE (2500 1205);
FORCEPROP 1 LAST HDL_POWER GND
J 2
(2500 1350);
DISPLAY 0.553191 (2500 1350);
PAINT GREEN (2500 1350);
DISPLAY INVISIBLE (2500 1350);
FORCEADD OFFPAGE..1
(-3700 1850);
FORCEPROP 2 LAST $XR5 54 
J 0
(-4431 1850);
DISPLAY 0.638298 (-4431 1850);
PAINT MONO (-4431 1850);
FORCEPROP 2 LAST $XR4 53 
J 0
(-4341 1850);
DISPLAY 0.638298 (-4341 1850);
PAINT MONO (-4341 1850);
FORCEPROP 2 LAST $XR3 52 
J 0
(-4251 1850);
DISPLAY 0.638298 (-4251 1850);
PAINT MONO (-4251 1850);
FORCEPROP 2 LAST $XR2 50 
J 0
(-4161 1850);
DISPLAY 0.638298 (-4161 1850);
PAINT MONO (-4161 1850);
FORCEPROP 2 LAST $XR1 49 
J 0
(-4071 1850);
DISPLAY 0.638298 (-4071 1850);
PAINT MONO (-4071 1850);
FORCEPROP 2 LAST $XR0 99 
J 0
(-3981 1850);
DISPLAY 0.638298 (-3981 1850);
PAINT MONO (-3981 1850);
FORCEPROP 2 LAST CDS_LIB mstr_standard
J 0
(-3700 1850);
DISPLAY 0.787234 (-3700 1850);
PAINT MONO (-3700 1850);
DISPLAY INVISIBLE (-3700 1850);
FORCEPROP 1 LAST OFFPAGE TRUE
J 0
(-3375 1725);
DISPLAY 0.936170 (-3375 1725);
PAINT GREEN (-3375 1725);
DISPLAY INVISIBLE (-3375 1725);
FORCEPROP 1 LAST COMMENT_BODY TRUE
J 0
(-3575 1750);
DISPLAY 0.936170 (-3575 1750);
PAINT GREEN (-3575 1750);
DISPLAY INVISIBLE (-3575 1750);
FORCEPROP 2 LAST PATH I169
J 0
(-3975 1900);
DISPLAY 0.787234 (-3975 1900);
PAINT ORANGE (-3975 1900);
DISPLAY INVISIBLE (-3975 1900);
FORCEADD PVTT_DEF..1
(-1000 2750);
FORCEPROP 3 LASTPIN (-1000 2700) SIG_NAME PVTT_DEF\g
J 0
(-990 2710);
DISPLAY 0.659574 (-990 2710);
PAINT MONO (-990 2710);
DISPLAY INVISIBLE (-990 2710);
FORCEPROP 1 LAST VOLTAGE 0.6V
J 0
(-1045 2707);
DISPLAY 0.340426 (-1045 2707);
PAINT SKYBLUE (-1045 2707);
DISPLAY INVISIBLE (-1045 2707);
FORCEPROP 2 LAST BOM_COST MEM
J 0
(-1000 2755);
PAINT ORANGE (-1000 2755);
DISPLAY INVISIBLE (-1000 2755);
FORCEPROP 2 LAST CDS_LIB mstr_symbols
J 0
(-1000 2750);
PAINT ORANGE (-1000 2750);
DISPLAY INVISIBLE (-1000 2750);
FORCEPROP 1 LAST BODY_TYPE PLUMBING
J 0
(-1045 2707);
DISPLAY 0.340426 (-1045 2707);
PAINT GREEN (-1045 2707);
DISPLAY INVISIBLE (-1045 2707);
FORCEPROP 1 LAST PATH I17
J 0
(-950 2775);
DISPLAY 0.872340 (-950 2775);
PAINT AQUA (-950 2775);
DISPLAY INVISIBLE (-950 2775);
FORCEPROP 2 LAST ROOM DDR4_CH_B
J 0
(-1000 2850);
DISPLAY 0.787234 (-1000 2850);
PAINT ORANGE (-1000 2850);
DISPLAY INVISIBLE (-1000 2850);
FORCEPROP 1 LAST HDL_POWER PVTT_DEF
J 1
(-1000 2800);
DISPLAY 0.872340 (-1000 2800);
PAINT GREEN (-1000 2800);
DISPLAY INVISIBLE (-1000 2800);
FORCEADD OFFPAGE..5
(-4075 2600);
FORCEPROP 2 LAST $XR23 94 
J 0
(-4569 2636);
DISPLAY 0.638298 (-4569 2636);
PAINT MONO (-4569 2636);
FORCEPROP 2 LAST $XR22 88 
J 0
(-4479 2636);
DISPLAY 0.638298 (-4479 2636);
PAINT MONO (-4479 2636);
FORCEPROP 2 LAST $XR21 87 
J 0
(-4389 2636);
DISPLAY 0.638298 (-4389 2636);
PAINT MONO (-4389 2636);
FORCEPROP 2 LAST $XR20 86 
J 0
(-4299 2636);
DISPLAY 0.638298 (-4299 2636);
PAINT MONO (-4299 2636);
FORCEPROP 2 LAST $XR19 85 
J 0
(-5109 2564);
DISPLAY 0.638298 (-5109 2564);
PAINT MONO (-5109 2564);
FORCEPROP 2 LAST $XR18 84 
J 0
(-5019 2564);
DISPLAY 0.638298 (-5019 2564);
PAINT MONO (-5019 2564);
FORCEPROP 2 LAST $XR17 83 
J 0
(-4929 2564);
DISPLAY 0.638298 (-4929 2564);
PAINT MONO (-4929 2564);
FORCEPROP 2 LAST $XR16 82 
J 0
(-4839 2564);
DISPLAY 0.638298 (-4839 2564);
PAINT MONO (-4839 2564);
FORCEPROP 2 LAST $XR15 81 
J 0
(-4749 2564);
DISPLAY 0.638298 (-4749 2564);
PAINT MONO (-4749 2564);
FORCEPROP 2 LAST $XR14 80 
J 0
(-4659 2564);
DISPLAY 0.638298 (-4659 2564);
PAINT MONO (-4659 2564);
FORCEPROP 2 LAST $XR13 79 
J 0
(-4569 2564);
DISPLAY 0.638298 (-4569 2564);
PAINT MONO (-4569 2564);
FORCEPROP 2 LAST $XR12 78 
J 0
(-4479 2564);
DISPLAY 0.638298 (-4479 2564);
PAINT MONO (-4479 2564);
FORCEPROP 2 LAST $XR11 77 
J 0
(-4389 2564);
DISPLAY 0.638298 (-4389 2564);
PAINT MONO (-4389 2564);
FORCEPROP 2 LAST $XR10 54 
J 0
(-4299 2564);
DISPLAY 0.638298 (-4299 2564);
PAINT MONO (-4299 2564);
FORCEPROP 2 LAST $XR9 53 
J 0
(-5109 2600);
DISPLAY 0.638298 (-5109 2600);
PAINT MONO (-5109 2600);
FORCEPROP 2 LAST $XR8 52 
J 0
(-5019 2600);
DISPLAY 0.638298 (-5019 2600);
PAINT MONO (-5019 2600);
FORCEPROP 2 LAST $XR7 50 
J 0
(-4929 2600);
DISPLAY 0.638298 (-4929 2600);
PAINT MONO (-4929 2600);
FORCEPROP 2 LAST $XR6 49 
J 0
(-4839 2600);
DISPLAY 0.638298 (-4839 2600);
PAINT MONO (-4839 2600);
FORCEPROP 2 LAST $XR5 48 
J 0
(-4749 2600);
DISPLAY 0.638298 (-4749 2600);
PAINT MONO (-4749 2600);
FORCEPROP 2 LAST $XR4 47 
J 0
(-4659 2600);
DISPLAY 0.638298 (-4659 2600);
PAINT MONO (-4659 2600);
FORCEPROP 2 LAST $XR3 46 
J 0
(-4569 2600);
DISPLAY 0.638298 (-4569 2600);
PAINT MONO (-4569 2600);
FORCEPROP 2 LAST $XR2 45 
J 0
(-4479 2600);
DISPLAY 0.638298 (-4479 2600);
PAINT MONO (-4479 2600);
FORCEPROP 2 LAST $XR1 44 
J 0
(-4389 2600);
DISPLAY 0.638298 (-4389 2600);
PAINT MONO (-4389 2600);
FORCEPROP 2 LAST $XR0 43 
J 0
(-4299 2600);
DISPLAY 0.638298 (-4299 2600);
PAINT MONO (-4299 2600);
FORCEPROP 2 LAST CDS_LIB mstr_standard
J 0
(-4075 2600);
DISPLAY 0.787234 (-4075 2600);
PAINT MONO (-4075 2600);
DISPLAY INVISIBLE (-4075 2600);
FORCEPROP 1 LAST OFFPAGE TRUE
J 0
(-3750 2475);
DISPLAY 1.404255 (-3750 2475);
PAINT GREEN (-3750 2475);
DISPLAY INVISIBLE (-3750 2475);
FORCEPROP 1 LAST COMMENT_BODY TRUE
J 0
(-3975 2525);
DISPLAY 1.404255 (-3975 2525);
PAINT GREEN (-3975 2525);
DISPLAY INVISIBLE (-3975 2525);
FORCEPROP 2 LAST PATH I171
J 0
(-4375 2650);
DISPLAY 0.787234 (-4375 2650);
PAINT ORANGE (-4375 2650);
DISPLAY INVISIBLE (-4375 2650);
FORCEADD OFFPAGE..6
(-3700 1900);
FORCEPROP 2 LASTPIN (-3650 1900) SIG_NAME SMB_DDR_DEF_VPP_SDA
J 0
(-3610 1910);
DISPLAY 0.617021 (-3610 1910);
PAINT ORANGE (-3610 1910);
FORCEPROP 2 LAST $XR5 99 
J 0
(-4429 1900);
DISPLAY 0.638298 (-4429 1900);
PAINT MONO (-4429 1900);
FORCEPROP 2 LAST $XR4 54 
J 0
(-4339 1900);
DISPLAY 0.638298 (-4339 1900);
PAINT MONO (-4339 1900);
FORCEPROP 2 LAST $XR3 53 
J 0
(-4249 1900);
DISPLAY 0.638298 (-4249 1900);
PAINT MONO (-4249 1900);
FORCEPROP 2 LAST $XR2 52 
J 0
(-4159 1900);
DISPLAY 0.638298 (-4159 1900);
PAINT MONO (-4159 1900);
FORCEPROP 2 LAST $XR1 50 
J 0
(-4069 1900);
DISPLAY 0.638298 (-4069 1900);
PAINT MONO (-4069 1900);
FORCEPROP 2 LAST $XR0 49 
J 0
(-3979 1900);
DISPLAY 0.638298 (-3979 1900);
PAINT MONO (-3979 1900);
FORCEPROP 2 LAST CDS_LIB mstr_standard
J 0
(-3700 1900);
DISPLAY 0.787234 (-3700 1900);
PAINT MONO (-3700 1900);
DISPLAY INVISIBLE (-3700 1900);
FORCEPROP 1 LAST OFFPAGE TRUE
J 0
(-3375 1775);
DISPLAY 0.936170 (-3375 1775);
PAINT GREEN (-3375 1775);
DISPLAY INVISIBLE (-3375 1775);
FORCEPROP 1 LAST COMMENT_BODY TRUE
J 0
(-3600 1825);
DISPLAY 0.936170 (-3600 1825);
PAINT GREEN (-3600 1825);
DISPLAY INVISIBLE (-3600 1825);
FORCEPROP 2 LAST PATH I172
J 0
(-4000 1950);
DISPLAY 0.787234 (-4000 1950);
PAINT ORANGE (-4000 1950);
DISPLAY INVISIBLE (-4000 1950);
FORCEADD GND..1
R 2
(-5200 1800);
FORCEPROP 3 LASTPIN (-5200 1850) SIG_NAME GND\g
J 0
(-5190 1860);
DISPLAY 0.659574 (-5190 1860);
PAINT MONO (-5190 1860);
DISPLAY INVISIBLE (-5190 1860);
FORCEPROP 1 LAST VOLTAGE 0
J 0
(-5200 1800);
PAINT SKYBLUE (-5200 1800);
DISPLAY INVISIBLE (-5200 1800);
FORCEPROP 1 LAST SIZE 1B
J 2
(-5275 1750);
DISPLAY 1.170213 (-5275 1750);
PAINT GREEN (-5275 1750);
DISPLAY INVISIBLE (-5275 1750);
FORCEPROP 2 LAST CDS_LIB mstr_symbols
J 0
(-5200 1800);
DISPLAY 0.787234 (-5200 1800);
PAINT MONO (-5200 1800);
DISPLAY INVISIBLE (-5200 1800);
FORCEPROP 2 LAST BOM_COST MEM
J 0
(-5200 1805);
PAINT ORANGE (-5200 1805);
DISPLAY INVISIBLE (-5200 1805);
FORCEPROP 1 LAST BODY_TYPE PLUMBING
J 2
(-5155 1757);
DISPLAY 0.340426 (-5155 1757);
PAINT GREEN (-5155 1757);
DISPLAY INVISIBLE (-5155 1757);
FORCEPROP 1 LAST PATH I174
J 2
(-5275 1800);
DISPLAY 1.404255 (-5275 1800);
PAINT GREEN (-5275 1800);
DISPLAY INVISIBLE (-5275 1800);
FORCEPROP 2 LAST ROOM DDR4_CH_B
J 0
(-5200 1805);
PAINT ORANGE (-5200 1805);
DISPLAY INVISIBLE (-5200 1805);
FORCEPROP 1 LAST HDL_POWER GND
J 2
(-5200 1950);
DISPLAY 0.553191 (-5200 1950);
PAINT GREEN (-5200 1950);
DISPLAY INVISIBLE (-5200 1950);
FORCEADD CAP_A..1
R 2
(-4650 1550);
FORCEPROP 1 LAST LOCATION C6L6
J 2
(-4700 1650);
DISPLAY 0.617021 (-4700 1650);
PAINT AQUA (-4700 1650);
FORCEPROP 1 LAST PART_NUMBER A36096-045
J 2
(-4700 1400);
DISPLAY 0.617021 (-4700 1400);
PAINT BLUE (-4700 1400);
FORCEPROP 1 LAST VALUE 0.01UF
J 2
(-4700 1600);
DISPLAY 0.617021 (-4700 1600);
PAINT SKYBLUE (-4700 1600);
FORCEPROP 1 LAST TOLERANCE 10%
J 2
(-4700 1500);
DISPLAY 0.617021 (-4700 1500);
PAINT SKYBLUE (-4700 1500);
FORCEPROP 1 LAST VOLTAGE 25V
J 2
(-4700 1550);
DISPLAY 0.617021 (-4700 1550);
PAINT SKYBLUE (-4700 1550);
FORCEPROP 1 LAST MATERIAL X7R
J 2
(-4700 1450);
DISPLAY 0.617021 (-4700 1450);
PAINT SKYBLUE (-4700 1450);
FORCEPROP 1 LAST PACK_TYPE 0402V
J 2
(-4700 1350);
DISPLAY 0.617021 (-4700 1350);
PAINT SKYBLUE (-4700 1350);
FORCEPROP 1 LASTPIN (-4650 1450) $PN 2
J 2
(-4660 1430);
DISPLAY 0.787234 (-4660 1430);
PAINT ORANGE (-4660 1430);
FORCEPROP 1 LASTPIN (-4650 1650) $PN 1
J 2
(-4660 1630);
DISPLAY 0.787234 (-4660 1630);
PAINT ORANGE (-4660 1630);
FORCEPROP 2 LAST CDS_LOCATION C6L6
J 2
(-4700 1650);
DISPLAY 0.617021 (-4700 1650);
PAINT AQUA (-4700 1650);
DISPLAY INVISIBLE (-4700 1650);
FORCEPROP 2 LAST BOM_COST MEM
J 0
(-4650 1550);
PAINT ORANGE (-4650 1550);
DISPLAY INVISIBLE (-4650 1550);
FORCEPROP 2 LAST CDS_LIB dev_discrete
J 0
(-4650 1550);
PAINT ORANGE (-4650 1550);
DISPLAY INVISIBLE (-4650 1550);
FORCEPROP 1 LAST PATH I175
J 2
(-4700 1700);
DISPLAY 0.978723 (-4700 1700);
PAINT WHITE (-4700 1700);
DISPLAY INVISIBLE (-4700 1700);
FORCEPROP 2 LAST ROOM DDR4_CH_E
J 0
(-4650 1550);
PAINT ORANGE (-4650 1550);
DISPLAY INVISIBLE (-4650 1550);
FORCEPROP 2 LAST SEC 1
J 0
(-4700 1750);
PAINT MONO (-4700 1750);
DISPLAY INVISIBLE (-4700 1750);
FORCEPROP 2 LAST SEC_TYPE 0402V
J 0
(-4700 1750);
DISPLAY 1.021277 (-4700 1750);
PAINT ORANGE (-4700 1750);
DISPLAY INVISIBLE (-4700 1750);
FORCEADD GND..1
R 2
(-4650 1300);
FORCEPROP 3 LASTPIN (-4650 1350) SIG_NAME GND\g
J 0
(-4640 1360);
DISPLAY 0.659574 (-4640 1360);
PAINT MONO (-4640 1360);
DISPLAY INVISIBLE (-4640 1360);
FORCEPROP 1 LAST VOLTAGE 0
J 0
(-4650 1300);
PAINT SKYBLUE (-4650 1300);
DISPLAY INVISIBLE (-4650 1300);
FORCEPROP 2 LAST BOM_COST MEM
J 0
(-4650 1305);
PAINT ORANGE (-4650 1305);
DISPLAY INVISIBLE (-4650 1305);
FORCEPROP 2 LAST CDS_LIB mstr_symbols
J 2
(-4650 1300);
PAINT ORANGE (-4650 1300);
DISPLAY INVISIBLE (-4650 1300);
FORCEPROP 1 LAST SIZE 1B
J 2
(-4725 1250);
DISPLAY 1.787234 (-4725 1250);
PAINT GREEN (-4725 1250);
DISPLAY INVISIBLE (-4725 1250);
FORCEPROP 1 LAST BODY_TYPE PLUMBING
J 2
(-4605 1257);
DISPLAY 0.340426 (-4605 1257);
PAINT GREEN (-4605 1257);
DISPLAY INVISIBLE (-4605 1257);
FORCEPROP 1 LAST PATH I176
J 2
(-4725 1300);
DISPLAY 1.404255 (-4725 1300);
PAINT GREEN (-4725 1300);
DISPLAY INVISIBLE (-4725 1300);
FORCEPROP 2 LAST ROOM DDR4_CH_B
J 0
(-4650 1305);
PAINT ORANGE (-4650 1305);
DISPLAY INVISIBLE (-4650 1305);
FORCEPROP 1 LAST HDL_POWER GND
J 2
(-4650 1450);
DISPLAY 1.404255 (-4650 1450);
PAINT GREEN (-4650 1450);
DISPLAY INVISIBLE (-4650 1450);
FORCEADD PVPP_DEF..1
(-850 3050);
FORCEPROP 3 LASTPIN (-850 3000) SIG_NAME PVPP_DEF\g
J 0
(-840 3010);
DISPLAY 0.659574 (-840 3010);
PAINT MONO (-840 3010);
DISPLAY INVISIBLE (-840 3010);
FORCEPROP 1 LAST VOLTAGE 2.5V
J 0
(-895 3007);
DISPLAY 0.340426 (-895 3007);
PAINT SKYBLUE (-895 3007);
DISPLAY INVISIBLE (-895 3007);
FORCEPROP 0 LAST BOM_COST MEM
J 0
(-850 3150);
PAINT ORANGE (-850 3150);
DISPLAY INVISIBLE (-850 3150);
FORCEPROP 2 LAST CDS_LIB mstr_symbols
J 0
(-850 3050);
PAINT ORANGE (-850 3050);
DISPLAY INVISIBLE (-850 3050);
FORCEPROP 1 LAST BODY_TYPE PLUMBING
J 0
(-895 3007);
DISPLAY 0.340426 (-895 3007);
PAINT GREEN (-895 3007);
DISPLAY INVISIBLE (-895 3007);
FORCEPROP 1 LAST PATH I177
J 0
(-800 3075);
DISPLAY 0.872340 (-800 3075);
PAINT AQUA (-800 3075);
DISPLAY INVISIBLE (-800 3075);
FORCEPROP 2 LAST ROOM DDR4_CH_B
J 0
(-850 3150);
PAINT ORANGE (-850 3150);
DISPLAY INVISIBLE (-850 3150);
FORCEPROP 1 LAST HDL_POWER PVPP_DEF
J 1
(-850 3100);
DISPLAY 0.872340 (-850 3100);
PAINT GREEN (-850 3100);
DISPLAY INVISIBLE (-850 3100);
FORCEADD PVPP_DEF..1
(-5200 2250);
FORCEPROP 3 LASTPIN (-5200 2200) SIG_NAME PVPP_DEF\g
J 0
(-5190 2210);
DISPLAY 0.659574 (-5190 2210);
PAINT MONO (-5190 2210);
DISPLAY INVISIBLE (-5190 2210);
FORCEPROP 1 LAST VOLTAGE 2.5V
J 0
(-5245 2207);
DISPLAY 0.340426 (-5245 2207);
PAINT SKYBLUE (-5245 2207);
DISPLAY INVISIBLE (-5245 2207);
FORCEPROP 0 LAST BOM_COST MEM
J 0
(-5200 2350);
PAINT ORANGE (-5200 2350);
DISPLAY INVISIBLE (-5200 2350);
FORCEPROP 2 LAST CDS_LIB mstr_symbols
J 0
(-5200 2250);
PAINT ORANGE (-5200 2250);
DISPLAY INVISIBLE (-5200 2250);
FORCEPROP 1 LAST BODY_TYPE PLUMBING
J 0
(-5245 2207);
DISPLAY 0.340426 (-5245 2207);
PAINT GREEN (-5245 2207);
DISPLAY INVISIBLE (-5245 2207);
FORCEPROP 1 LAST PATH I178
J 0
(-5150 2275);
DISPLAY 0.872340 (-5150 2275);
PAINT AQUA (-5150 2275);
DISPLAY INVISIBLE (-5150 2275);
FORCEPROP 2 LAST ROOM DDR4_CH_B
J 0
(-5200 2350);
PAINT ORANGE (-5200 2350);
DISPLAY INVISIBLE (-5200 2350);
FORCEPROP 1 LAST HDL_POWER PVPP_DEF
J 1
(-5200 2300);
DISPLAY 0.872340 (-5200 2300);
PAINT GREEN (-5200 2300);
DISPLAY INVISIBLE (-5200 2300);
FORCEADD OFFPAGE..1
(-3750 1450);
FORCEPROP 2 LAST $XR5 54 
J 0
(-4421 1450);
DISPLAY 0.638298 (-4421 1450);
PAINT MONO (-4421 1450);
FORCEPROP 2 LAST $XR4 53 
J 0
(-4331 1450);
DISPLAY 0.638298 (-4331 1450);
PAINT MONO (-4331 1450);
FORCEPROP 2 LAST $XR3 52 
J 0
(-4241 1450);
DISPLAY 0.638298 (-4241 1450);
PAINT MONO (-4241 1450);
FORCEPROP 2 LAST $XR2 50 
J 0
(-4151 1450);
DISPLAY 0.638298 (-4151 1450);
PAINT MONO (-4151 1450);
FORCEPROP 2 LAST $XR1 49 
J 0
(-4061 1450);
DISPLAY 0.638298 (-4061 1450);
PAINT MONO (-4061 1450);
FORCEPROP 2 LAST $XR0 89 
J 0
(-3971 1450);
DISPLAY 0.638298 (-3971 1450);
PAINT MONO (-3971 1450);
FORCEPROP 2 LAST CDS_LIB mstr_standard
J 0
(-3750 1450);
PAINT ORANGE (-3750 1450);
DISPLAY INVISIBLE (-3750 1450);
FORCEPROP 1 LAST OFFPAGE TRUE
J 0
(-3425 1325);
DISPLAY 0.936170 (-3425 1325);
PAINT GREEN (-3425 1325);
DISPLAY INVISIBLE (-3425 1325);
FORCEPROP 1 LAST COMMENT_BODY TRUE
J 0
(-3625 1350);
DISPLAY 0.936170 (-3625 1350);
PAINT GREEN (-3625 1350);
DISPLAY INVISIBLE (-3625 1350);
FORCEPROP 2 LAST PATH I179
J 0
(-3700 1525);
PAINT ORANGE (-3700 1525);
DISPLAY INVISIBLE (-3700 1525);
FORCEADD TAP..6
(-3500 3700);
FORCEPROP 3 LASTPIN (-3450 3700) SIG_NAME M_E_CLK_DP<1>
J 0
(-3440 3710);
DISPLAY 0.659574 (-3440 3710);
PAINT MONO (-3440 3710);
DISPLAY INVISIBLE (-3440 3710);
FORCEPROP 1 LASTPIN (-3450 3700) BN 1
J 0
(-3502 3708);
DISPLAY 0.617021 (-3502 3708);
PAINT PINK (-3502 3708);
FORCEPROP 2 LAST CDS_LIB mstr_standard
J 0
(-3500 3700);
PAINT MONO (-3500 3700);
DISPLAY INVISIBLE (-3500 3700);
FORCEPROP 1 LAST BODY_TYPE PLUMBING
J 0
(-3500 3650);
DISPLAY 1.234043 (-3500 3650);
PAINT GREEN (-3500 3650);
DISPLAY INVISIBLE (-3500 3650);
FORCEPROP 1 LAST HDL_TAP TRUE
J 0
(-3175 3575);
DISPLAY 1.234043 (-3175 3575);
PAINT GREEN (-3175 3575);
DISPLAY INVISIBLE (-3175 3575);
FORCEPROP 1 LAST PATH I183
J 0
(-3502 3700);
DISPLAY 0.872340 (-3502 3700);
PAINT GREEN (-3502 3700);
DISPLAY INVISIBLE (-3502 3700);
FORCEADD TAP..6
(-3650 3650);
FORCEPROP 3 LASTPIN (-3600 3650) SIG_NAME M_E_CLK_DN<1>
J 0
(-3590 3660);
DISPLAY 0.659574 (-3590 3660);
PAINT MONO (-3590 3660);
DISPLAY INVISIBLE (-3590 3660);
FORCEPROP 1 LASTPIN (-3600 3650) BN 1
J 0
(-3652 3658);
DISPLAY 0.617021 (-3652 3658);
PAINT PINK (-3652 3658);
FORCEPROP 2 LAST CDS_LIB mstr_standard
J 0
(-3650 3650);
PAINT MONO (-3650 3650);
DISPLAY INVISIBLE (-3650 3650);
FORCEPROP 1 LAST BODY_TYPE PLUMBING
J 0
(-3650 3600);
DISPLAY 1.234043 (-3650 3600);
PAINT GREEN (-3650 3600);
DISPLAY INVISIBLE (-3650 3600);
FORCEPROP 1 LAST HDL_TAP TRUE
J 0
(-3325 3525);
DISPLAY 1.234043 (-3325 3525);
PAINT GREEN (-3325 3525);
DISPLAY INVISIBLE (-3325 3525);
FORCEPROP 1 LAST PATH I184
J 0
(-3652 3650);
DISPLAY 0.872340 (-3652 3650);
PAINT GREEN (-3652 3650);
DISPLAY INVISIBLE (-3652 3650);
FORCEADD P12V_NVDIMM_DEF..1
(550 3125);
FORCEPROP 3 LASTPIN (550 3075) SIG_NAME P12V_NVDIMM_DEF\g
J 0
(560 3085);
DISPLAY 0.659574 (560 3085);
PAINT MONO (560 3085);
DISPLAY INVISIBLE (560 3085);
FORCEPROP 1 LAST VOLTAGE 12.0
J 0
(505 3082);
DISPLAY 0.340426 (505 3082);
PAINT SKYBLUE (505 3082);
DISPLAY INVISIBLE (505 3082);
FORCEPROP 2 LAST CDS_LIB mstr_symbols
J 0
(550 3125);
PAINT ORANGE (550 3125);
DISPLAY INVISIBLE (550 3125);
FORCEPROP 1 LAST BODY_TYPE PLUMBING
J 0
(505 3082);
DISPLAY 0.340426 (505 3082);
PAINT GREEN (505 3082);
DISPLAY INVISIBLE (505 3082);
FORCEPROP 1 LAST PATH I185
J 0
(600 3150);
DISPLAY 0.872340 (600 3150);
PAINT AQUA (600 3150);
DISPLAY INVISIBLE (600 3150);
FORCEPROP 1 LAST HDL_POWER P12V_NVDIMM_DEF
J 1
(550 3175);
DISPLAY 0.872340 (550 3175);
PAINT GREEN (550 3175);
DISPLAY INVISIBLE (550 3175);
FORCEADD TAP..6
R 2
(900 4500);
FORCEPROP 3 LASTPIN (850 4500) SIG_NAME M_E_DQS_DN<11>
J 0
(860 4510);
DISPLAY 0.659574 (860 4510);
PAINT MONO (860 4510);
DISPLAY INVISIBLE (860 4510);
FORCEPROP 1 LASTPIN (850 4500) BN 11
J 2
(900 4510);
DISPLAY 0.617021 (900 4510);
PAINT PINK (900 4510);
FORCEPROP 2 LAST CDS_LIB mstr_standard
J 0
(900 4500);
DISPLAY 0.787234 (900 4500);
PAINT MONO (900 4500);
DISPLAY INVISIBLE (900 4500);
FORCEPROP 1 LAST BODY_TYPE PLUMBING
J 2
(900 4450);
DISPLAY 1.234043 (900 4450);
PAINT GREEN (900 4450);
DISPLAY INVISIBLE (900 4450);
FORCEPROP 1 LAST HDL_TAP TRUE
J 2
(575 4375);
DISPLAY 1.234043 (575 4375);
PAINT GREEN (575 4375);
DISPLAY INVISIBLE (575 4375);
FORCEPROP 1 LAST PATH I19
J 2
(900 4500);
DISPLAY 0.936170 (900 4500);
PAINT GREEN (900 4500);
DISPLAY INVISIBLE (900 4500);
FORCEADD OFFPAGE..3
(1600 5150);
FORCEPROP 2 LAST $XR1 52 
J 0
(1904 5150);
DISPLAY 0.638298 (1904 5150);
PAINT MONO (1904 5150);
FORCEPROP 2 LAST $XR0 27 
J 0
(1814 5150);
DISPLAY 0.638298 (1814 5150);
PAINT MONO (1814 5150);
FORCEPROP 2 LAST CDS_LIB mstr_standard
J 0
(1600 5150);
DISPLAY 0.787234 (1600 5150);
PAINT MONO (1600 5150);
DISPLAY INVISIBLE (1600 5150);
FORCEPROP 1 LAST OFFPAGE TRUE
J 0
(1925 5025);
DISPLAY 0.936170 (1925 5025);
PAINT GREEN (1925 5025);
DISPLAY INVISIBLE (1925 5025);
FORCEPROP 1 LAST COMMENT_BODY TRUE
J 0
(1550 5050);
DISPLAY 0.936170 (1550 5050);
PAINT GREEN (1550 5050);
DISPLAY INVISIBLE (1550 5050);
FORCEPROP 2 LAST PATH I2
J 0
(1800 5225);
DISPLAY 0.787234 (1800 5225);
PAINT MONO (1800 5225);
DISPLAY INVISIBLE (1800 5225);
FORCEADD TAP..6
R 2
(900 4400);
FORCEPROP 3 LASTPIN (850 4400) SIG_NAME M_E_DQS_DN<10>
J 0
(860 4410);
DISPLAY 0.659574 (860 4410);
PAINT MONO (860 4410);
DISPLAY INVISIBLE (860 4410);
FORCEPROP 1 LASTPIN (850 4400) BN 10
J 2
(900 4410);
DISPLAY 0.617021 (900 4410);
PAINT PINK (900 4410);
FORCEPROP 2 LAST CDS_LIB mstr_standard
J 0
(900 4400);
DISPLAY 0.787234 (900 4400);
PAINT MONO (900 4400);
DISPLAY INVISIBLE (900 4400);
FORCEPROP 1 LAST BODY_TYPE PLUMBING
J 2
(900 4350);
DISPLAY 1.234043 (900 4350);
PAINT GREEN (900 4350);
DISPLAY INVISIBLE (900 4350);
FORCEPROP 1 LAST HDL_TAP TRUE
J 2
(575 4275);
DISPLAY 1.234043 (575 4275);
PAINT GREEN (575 4275);
DISPLAY INVISIBLE (575 4275);
FORCEPROP 1 LAST PATH I20
J 2
(900 4400);
DISPLAY 0.936170 (900 4400);
PAINT GREEN (900 4400);
DISPLAY INVISIBLE (900 4400);
FORCEADD TAP..6
R 2
(900 4300);
FORCEPROP 3 LASTPIN (850 4300) SIG_NAME M_E_DQS_DN<9>
J 0
(860 4310);
DISPLAY 0.659574 (860 4310);
PAINT MONO (860 4310);
DISPLAY INVISIBLE (860 4310);
FORCEPROP 1 LASTPIN (850 4300) BN 9
J 2
(900 4310);
DISPLAY 0.617021 (900 4310);
PAINT PINK (900 4310);
FORCEPROP 2 LAST CDS_LIB mstr_standard
J 0
(900 4300);
DISPLAY 0.787234 (900 4300);
PAINT MONO (900 4300);
DISPLAY INVISIBLE (900 4300);
FORCEPROP 1 LAST BODY_TYPE PLUMBING
J 2
(900 4250);
DISPLAY 1.234043 (900 4250);
PAINT GREEN (900 4250);
DISPLAY INVISIBLE (900 4250);
FORCEPROP 1 LAST HDL_TAP TRUE
J 2
(575 4175);
DISPLAY 1.234043 (575 4175);
PAINT GREEN (575 4175);
DISPLAY INVISIBLE (575 4175);
FORCEPROP 1 LAST PATH I21
J 2
(900 4300);
DISPLAY 0.936170 (900 4300);
PAINT GREEN (900 4300);
DISPLAY INVISIBLE (900 4300);
FORCEADD TAP..6
R 2
(900 4200);
FORCEPROP 3 LASTPIN (850 4200) SIG_NAME M_E_DQS_DN<8>
J 0
(860 4210);
DISPLAY 0.659574 (860 4210);
PAINT MONO (860 4210);
DISPLAY INVISIBLE (860 4210);
FORCEPROP 1 LASTPIN (850 4200) BN 8
J 2
(900 4210);
DISPLAY 0.617021 (900 4210);
PAINT PINK (900 4210);
FORCEPROP 2 LAST CDS_LIB mstr_standard
J 0
(900 4200);
DISPLAY 0.787234 (900 4200);
PAINT MONO (900 4200);
DISPLAY INVISIBLE (900 4200);
FORCEPROP 1 LAST BODY_TYPE PLUMBING
J 2
(900 4150);
DISPLAY 1.234043 (900 4150);
PAINT GREEN (900 4150);
DISPLAY INVISIBLE (900 4150);
FORCEPROP 1 LAST HDL_TAP TRUE
J 2
(575 4075);
DISPLAY 1.234043 (575 4075);
PAINT GREEN (575 4075);
DISPLAY INVISIBLE (575 4075);
FORCEPROP 1 LAST PATH I22
J 2
(900 4200);
DISPLAY 0.936170 (900 4200);
PAINT GREEN (900 4200);
DISPLAY INVISIBLE (900 4200);
FORCEADD TAP..6
R 2
(900 4100);
FORCEPROP 3 LASTPIN (850 4100) SIG_NAME M_E_DQS_DN<7>
J 0
(860 4110);
DISPLAY 0.659574 (860 4110);
PAINT MONO (860 4110);
DISPLAY INVISIBLE (860 4110);
FORCEPROP 1 LASTPIN (850 4100) BN 7
J 2
(900 4110);
DISPLAY 0.617021 (900 4110);
PAINT PINK (900 4110);
FORCEPROP 2 LAST CDS_LIB mstr_standard
J 0
(900 4100);
DISPLAY 0.787234 (900 4100);
PAINT MONO (900 4100);
DISPLAY INVISIBLE (900 4100);
FORCEPROP 1 LAST BODY_TYPE PLUMBING
J 2
(900 4050);
DISPLAY 1.234043 (900 4050);
PAINT GREEN (900 4050);
DISPLAY INVISIBLE (900 4050);
FORCEPROP 1 LAST HDL_TAP TRUE
J 2
(575 3975);
DISPLAY 1.234043 (575 3975);
PAINT GREEN (575 3975);
DISPLAY INVISIBLE (575 3975);
FORCEPROP 1 LAST PATH I23
J 2
(900 4100);
DISPLAY 0.936170 (900 4100);
PAINT GREEN (900 4100);
DISPLAY INVISIBLE (900 4100);
FORCEADD TAP..6
R 2
(700 4350);
FORCEPROP 3 LASTPIN (650 4350) SIG_NAME M_E_DQS_DP<9>
J 0
(660 4360);
DISPLAY 0.659574 (660 4360);
PAINT MONO (660 4360);
DISPLAY INVISIBLE (660 4360);
FORCEPROP 1 LASTPIN (650 4350) BN 9
J 2
(700 4360);
DISPLAY 0.617021 (700 4360);
PAINT PINK (700 4360);
FORCEPROP 2 LAST CDS_LIB mstr_standard
J 0
(700 4350);
DISPLAY 0.787234 (700 4350);
PAINT MONO (700 4350);
DISPLAY INVISIBLE (700 4350);
FORCEPROP 1 LAST BODY_TYPE PLUMBING
J 2
(700 4300);
DISPLAY 1.234043 (700 4300);
PAINT GREEN (700 4300);
DISPLAY INVISIBLE (700 4300);
FORCEPROP 1 LAST HDL_TAP TRUE
J 2
(375 4225);
DISPLAY 1.234043 (375 4225);
PAINT GREEN (375 4225);
DISPLAY INVISIBLE (375 4225);
FORCEPROP 1 LAST PATH I24
J 2
(700 4350);
DISPLAY 0.936170 (700 4350);
PAINT GREEN (700 4350);
DISPLAY INVISIBLE (700 4350);
FORCEADD TAP..6
R 2
(700 4450);
FORCEPROP 3 LASTPIN (650 4450) SIG_NAME M_E_DQS_DP<10>
J 0
(660 4460);
DISPLAY 0.659574 (660 4460);
PAINT MONO (660 4460);
DISPLAY INVISIBLE (660 4460);
FORCEPROP 1 LASTPIN (650 4450) BN 10
J 2
(700 4460);
DISPLAY 0.617021 (700 4460);
PAINT PINK (700 4460);
FORCEPROP 2 LAST CDS_LIB mstr_standard
J 0
(700 4450);
DISPLAY 0.787234 (700 4450);
PAINT MONO (700 4450);
DISPLAY INVISIBLE (700 4450);
FORCEPROP 1 LAST BODY_TYPE PLUMBING
J 2
(700 4400);
DISPLAY 1.234043 (700 4400);
PAINT GREEN (700 4400);
DISPLAY INVISIBLE (700 4400);
FORCEPROP 1 LAST HDL_TAP TRUE
J 2
(375 4325);
DISPLAY 1.234043 (375 4325);
PAINT GREEN (375 4325);
DISPLAY INVISIBLE (375 4325);
FORCEPROP 1 LAST PATH I25
J 2
(700 4450);
DISPLAY 0.936170 (700 4450);
PAINT GREEN (700 4450);
DISPLAY INVISIBLE (700 4450);
FORCEADD TAP..6
R 2
(700 4250);
FORCEPROP 3 LASTPIN (650 4250) SIG_NAME M_E_DQS_DP<8>
J 0
(660 4260);
DISPLAY 0.659574 (660 4260);
PAINT MONO (660 4260);
DISPLAY INVISIBLE (660 4260);
FORCEPROP 1 LASTPIN (650 4250) BN 8
J 2
(700 4260);
DISPLAY 0.617021 (700 4260);
PAINT PINK (700 4260);
FORCEPROP 2 LAST CDS_LIB mstr_standard
J 0
(700 4250);
DISPLAY 0.787234 (700 4250);
PAINT MONO (700 4250);
DISPLAY INVISIBLE (700 4250);
FORCEPROP 1 LAST BODY_TYPE PLUMBING
J 2
(700 4200);
DISPLAY 1.234043 (700 4200);
PAINT GREEN (700 4200);
DISPLAY INVISIBLE (700 4200);
FORCEPROP 1 LAST HDL_TAP TRUE
J 2
(375 4125);
DISPLAY 1.234043 (375 4125);
PAINT GREEN (375 4125);
DISPLAY INVISIBLE (375 4125);
FORCEPROP 1 LAST PATH I26
J 2
(700 4250);
DISPLAY 0.936170 (700 4250);
PAINT GREEN (700 4250);
DISPLAY INVISIBLE (700 4250);
FORCEADD TAP..6
R 2
(700 4050);
FORCEPROP 3 LASTPIN (650 4050) SIG_NAME M_E_DQS_DP<6>
J 0
(660 4060);
DISPLAY 0.659574 (660 4060);
PAINT MONO (660 4060);
DISPLAY INVISIBLE (660 4060);
FORCEPROP 1 LASTPIN (650 4050) BN 6
J 2
(700 4060);
DISPLAY 0.617021 (700 4060);
PAINT PINK (700 4060);
FORCEPROP 2 LAST CDS_LIB mstr_standard
J 0
(700 4050);
DISPLAY 0.787234 (700 4050);
PAINT MONO (700 4050);
DISPLAY INVISIBLE (700 4050);
FORCEPROP 1 LAST BODY_TYPE PLUMBING
J 2
(700 4000);
DISPLAY 1.234043 (700 4000);
PAINT GREEN (700 4000);
DISPLAY INVISIBLE (700 4000);
FORCEPROP 1 LAST HDL_TAP TRUE
J 2
(375 3925);
DISPLAY 1.234043 (375 3925);
PAINT GREEN (375 3925);
DISPLAY INVISIBLE (375 3925);
FORCEPROP 1 LAST PATH I27
J 2
(700 4050);
DISPLAY 0.936170 (700 4050);
PAINT GREEN (700 4050);
DISPLAY INVISIBLE (700 4050);
FORCEADD TAP..6
R 2
(700 4150);
FORCEPROP 3 LASTPIN (650 4150) SIG_NAME M_E_DQS_DP<7>
J 0
(660 4160);
DISPLAY 0.659574 (660 4160);
PAINT MONO (660 4160);
DISPLAY INVISIBLE (660 4160);
FORCEPROP 1 LASTPIN (650 4150) BN 7
J 2
(700 4160);
DISPLAY 0.617021 (700 4160);
PAINT PINK (700 4160);
FORCEPROP 2 LAST CDS_LIB mstr_standard
J 0
(700 4150);
DISPLAY 0.787234 (700 4150);
PAINT MONO (700 4150);
DISPLAY INVISIBLE (700 4150);
FORCEPROP 1 LAST BODY_TYPE PLUMBING
J 2
(700 4100);
DISPLAY 1.234043 (700 4100);
PAINT GREEN (700 4100);
DISPLAY INVISIBLE (700 4100);
FORCEPROP 1 LAST HDL_TAP TRUE
J 2
(375 4025);
DISPLAY 1.234043 (375 4025);
PAINT GREEN (375 4025);
DISPLAY INVISIBLE (375 4025);
FORCEPROP 1 LAST PATH I28
J 2
(700 4150);
DISPLAY 0.936170 (700 4150);
PAINT GREEN (700 4150);
DISPLAY INVISIBLE (700 4150);
FORCEADD TAP..6
R 2
(900 4000);
FORCEPROP 3 LASTPIN (850 4000) SIG_NAME M_E_DQS_DN<6>
J 0
(860 4010);
DISPLAY 0.659574 (860 4010);
PAINT MONO (860 4010);
DISPLAY INVISIBLE (860 4010);
FORCEPROP 1 LASTPIN (850 4000) BN 6
J 2
(900 4010);
DISPLAY 0.617021 (900 4010);
PAINT PINK (900 4010);
FORCEPROP 2 LAST CDS_LIB mstr_standard
J 0
(900 4000);
DISPLAY 0.787234 (900 4000);
PAINT MONO (900 4000);
DISPLAY INVISIBLE (900 4000);
FORCEPROP 1 LAST BODY_TYPE PLUMBING
J 2
(900 3950);
DISPLAY 1.234043 (900 3950);
PAINT GREEN (900 3950);
DISPLAY INVISIBLE (900 3950);
FORCEPROP 1 LAST HDL_TAP TRUE
J 2
(575 3875);
DISPLAY 1.234043 (575 3875);
PAINT GREEN (575 3875);
DISPLAY INVISIBLE (575 3875);
FORCEPROP 1 LAST PATH I29
J 2
(900 4000);
DISPLAY 0.936170 (900 4000);
PAINT GREEN (900 4000);
DISPLAY INVISIBLE (900 4000);
FORCEADD TAP..6
R 2
(900 5100);
FORCEPROP 3 LASTPIN (850 5100) SIG_NAME M_E_DQS_DN<17>
J 0
(860 5110);
DISPLAY 0.659574 (860 5110);
PAINT MONO (860 5110);
DISPLAY INVISIBLE (860 5110);
FORCEPROP 1 LASTPIN (850 5100) BN 17
J 2
(900 5110);
DISPLAY 0.617021 (900 5110);
PAINT PINK (900 5110);
FORCEPROP 2 LAST CDS_LIB mstr_standard
J 2
(900 5100);
DISPLAY 0.787234 (900 5100);
PAINT MONO (900 5100);
DISPLAY INVISIBLE (900 5100);
FORCEPROP 1 LAST BODY_TYPE PLUMBING
J 2
(900 5050);
DISPLAY 1.234043 (900 5050);
PAINT GREEN (900 5050);
DISPLAY INVISIBLE (900 5050);
FORCEPROP 1 LAST HDL_TAP TRUE
J 2
(575 4975);
DISPLAY 1.234043 (575 4975);
PAINT GREEN (575 4975);
DISPLAY INVISIBLE (575 4975);
FORCEPROP 1 LAST PATH I3
J 2
(900 5100);
DISPLAY 0.936170 (900 5100);
PAINT GREEN (900 5100);
DISPLAY INVISIBLE (900 5100);
FORCEADD TAP..6
R 2
(900 3900);
FORCEPROP 3 LASTPIN (850 3900) SIG_NAME M_E_DQS_DN<5>
J 0
(860 3910);
DISPLAY 0.659574 (860 3910);
PAINT MONO (860 3910);
DISPLAY INVISIBLE (860 3910);
FORCEPROP 1 LASTPIN (850 3900) BN 5
J 2
(900 3910);
DISPLAY 0.617021 (900 3910);
PAINT PINK (900 3910);
FORCEPROP 2 LAST CDS_LIB mstr_standard
J 0
(900 3900);
DISPLAY 0.787234 (900 3900);
PAINT MONO (900 3900);
DISPLAY INVISIBLE (900 3900);
FORCEPROP 1 LAST BODY_TYPE PLUMBING
J 2
(900 3850);
DISPLAY 1.234043 (900 3850);
PAINT GREEN (900 3850);
DISPLAY INVISIBLE (900 3850);
FORCEPROP 1 LAST HDL_TAP TRUE
J 2
(575 3775);
DISPLAY 1.234043 (575 3775);
PAINT GREEN (575 3775);
DISPLAY INVISIBLE (575 3775);
FORCEPROP 1 LAST PATH I30
J 2
(900 3900);
DISPLAY 0.936170 (900 3900);
PAINT GREEN (900 3900);
DISPLAY INVISIBLE (900 3900);
FORCEADD TAP..6
R 2
(900 3800);
FORCEPROP 3 LASTPIN (850 3800) SIG_NAME M_E_DQS_DN<4>
J 0
(860 3810);
DISPLAY 0.659574 (860 3810);
PAINT MONO (860 3810);
DISPLAY INVISIBLE (860 3810);
FORCEPROP 1 LASTPIN (850 3800) BN 4
J 2
(900 3810);
DISPLAY 0.617021 (900 3810);
PAINT PINK (900 3810);
FORCEPROP 2 LAST CDS_LIB mstr_standard
J 0
(900 3800);
DISPLAY 0.787234 (900 3800);
PAINT MONO (900 3800);
DISPLAY INVISIBLE (900 3800);
FORCEPROP 1 LAST BODY_TYPE PLUMBING
J 2
(900 3750);
DISPLAY 1.234043 (900 3750);
PAINT GREEN (900 3750);
DISPLAY INVISIBLE (900 3750);
FORCEPROP 1 LAST HDL_TAP TRUE
J 2
(575 3675);
DISPLAY 1.234043 (575 3675);
PAINT GREEN (575 3675);
DISPLAY INVISIBLE (575 3675);
FORCEPROP 1 LAST PATH I31
J 2
(900 3800);
DISPLAY 0.936170 (900 3800);
PAINT GREEN (900 3800);
DISPLAY INVISIBLE (900 3800);
FORCEADD TAP..6
R 2
(900 3700);
FORCEPROP 3 LASTPIN (850 3700) SIG_NAME M_E_DQS_DN<3>
J 0
(860 3710);
DISPLAY 0.659574 (860 3710);
PAINT MONO (860 3710);
DISPLAY INVISIBLE (860 3710);
FORCEPROP 1 LASTPIN (850 3700) BN 3
J 2
(900 3710);
DISPLAY 0.617021 (900 3710);
PAINT PINK (900 3710);
FORCEPROP 2 LAST CDS_LIB mstr_standard
J 0
(900 3700);
DISPLAY 0.787234 (900 3700);
PAINT MONO (900 3700);
DISPLAY INVISIBLE (900 3700);
FORCEPROP 1 LAST BODY_TYPE PLUMBING
J 2
(900 3650);
DISPLAY 1.234043 (900 3650);
PAINT GREEN (900 3650);
DISPLAY INVISIBLE (900 3650);
FORCEPROP 1 LAST HDL_TAP TRUE
J 2
(575 3575);
DISPLAY 1.234043 (575 3575);
PAINT GREEN (575 3575);
DISPLAY INVISIBLE (575 3575);
FORCEPROP 1 LAST PATH I32
J 2
(900 3700);
DISPLAY 0.936170 (900 3700);
PAINT GREEN (900 3700);
DISPLAY INVISIBLE (900 3700);
FORCEADD TAP..6
R 2
(900 3600);
FORCEPROP 3 LASTPIN (850 3600) SIG_NAME M_E_DQS_DN<2>
J 0
(860 3610);
DISPLAY 0.659574 (860 3610);
PAINT MONO (860 3610);
DISPLAY INVISIBLE (860 3610);
FORCEPROP 1 LASTPIN (850 3600) BN 2
J 2
(900 3610);
DISPLAY 0.617021 (900 3610);
PAINT PINK (900 3610);
FORCEPROP 2 LAST CDS_LIB mstr_standard
J 0
(900 3600);
DISPLAY 0.787234 (900 3600);
PAINT MONO (900 3600);
DISPLAY INVISIBLE (900 3600);
FORCEPROP 1 LAST BODY_TYPE PLUMBING
J 2
(900 3550);
DISPLAY 1.234043 (900 3550);
PAINT GREEN (900 3550);
DISPLAY INVISIBLE (900 3550);
FORCEPROP 1 LAST HDL_TAP TRUE
J 2
(575 3475);
DISPLAY 1.234043 (575 3475);
PAINT GREEN (575 3475);
DISPLAY INVISIBLE (575 3475);
FORCEPROP 1 LAST PATH I33
J 2
(900 3600);
DISPLAY 0.936170 (900 3600);
PAINT GREEN (900 3600);
DISPLAY INVISIBLE (900 3600);
FORCEADD TAP..6
R 2
(700 3850);
FORCEPROP 3 LASTPIN (650 3850) SIG_NAME M_E_DQS_DP<4>
J 0
(660 3860);
DISPLAY 0.659574 (660 3860);
PAINT MONO (660 3860);
DISPLAY INVISIBLE (660 3860);
FORCEPROP 1 LASTPIN (650 3850) BN 4
J 2
(700 3860);
DISPLAY 0.617021 (700 3860);
PAINT PINK (700 3860);
FORCEPROP 2 LAST CDS_LIB mstr_standard
J 0
(700 3850);
DISPLAY 0.787234 (700 3850);
PAINT MONO (700 3850);
DISPLAY INVISIBLE (700 3850);
FORCEPROP 1 LAST BODY_TYPE PLUMBING
J 2
(700 3800);
DISPLAY 1.234043 (700 3800);
PAINT GREEN (700 3800);
DISPLAY INVISIBLE (700 3800);
FORCEPROP 1 LAST HDL_TAP TRUE
J 2
(375 3725);
DISPLAY 1.234043 (375 3725);
PAINT GREEN (375 3725);
DISPLAY INVISIBLE (375 3725);
FORCEPROP 1 LAST PATH I34
J 2
(700 3850);
DISPLAY 0.936170 (700 3850);
PAINT GREEN (700 3850);
DISPLAY INVISIBLE (700 3850);
FORCEADD TAP..6
R 2
(700 3950);
FORCEPROP 3 LASTPIN (650 3950) SIG_NAME M_E_DQS_DP<5>
J 0
(660 3960);
DISPLAY 0.659574 (660 3960);
PAINT MONO (660 3960);
DISPLAY INVISIBLE (660 3960);
FORCEPROP 1 LASTPIN (650 3950) BN 5
J 2
(700 3960);
DISPLAY 0.617021 (700 3960);
PAINT PINK (700 3960);
FORCEPROP 2 LAST CDS_LIB mstr_standard
J 0
(700 3950);
DISPLAY 0.787234 (700 3950);
PAINT MONO (700 3950);
DISPLAY INVISIBLE (700 3950);
FORCEPROP 1 LAST BODY_TYPE PLUMBING
J 2
(700 3900);
DISPLAY 1.234043 (700 3900);
PAINT GREEN (700 3900);
DISPLAY INVISIBLE (700 3900);
FORCEPROP 1 LAST HDL_TAP TRUE
J 2
(375 3825);
DISPLAY 1.234043 (375 3825);
PAINT GREEN (375 3825);
DISPLAY INVISIBLE (375 3825);
FORCEPROP 1 LAST PATH I35
J 2
(700 3950);
DISPLAY 0.936170 (700 3950);
PAINT GREEN (700 3950);
DISPLAY INVISIBLE (700 3950);
FORCEADD TAP..6
R 2
(700 3750);
FORCEPROP 3 LASTPIN (650 3750) SIG_NAME M_E_DQS_DP<3>
J 0
(660 3760);
DISPLAY 0.659574 (660 3760);
PAINT MONO (660 3760);
DISPLAY INVISIBLE (660 3760);
FORCEPROP 1 LASTPIN (650 3750) BN 3
J 2
(700 3760);
DISPLAY 0.617021 (700 3760);
PAINT PINK (700 3760);
FORCEPROP 2 LAST CDS_LIB mstr_standard
J 0
(700 3750);
DISPLAY 0.787234 (700 3750);
PAINT MONO (700 3750);
DISPLAY INVISIBLE (700 3750);
FORCEPROP 1 LAST BODY_TYPE PLUMBING
J 2
(700 3700);
DISPLAY 1.234043 (700 3700);
PAINT GREEN (700 3700);
DISPLAY INVISIBLE (700 3700);
FORCEPROP 1 LAST HDL_TAP TRUE
J 2
(375 3625);
DISPLAY 1.234043 (375 3625);
PAINT GREEN (375 3625);
DISPLAY INVISIBLE (375 3625);
FORCEPROP 1 LAST PATH I36
J 2
(700 3750);
DISPLAY 0.936170 (700 3750);
PAINT GREEN (700 3750);
DISPLAY INVISIBLE (700 3750);
FORCEADD TAP..6
R 2
(700 3650);
FORCEPROP 3 LASTPIN (650 3650) SIG_NAME M_E_DQS_DP<2>
J 0
(660 3660);
DISPLAY 0.659574 (660 3660);
PAINT MONO (660 3660);
DISPLAY INVISIBLE (660 3660);
FORCEPROP 1 LASTPIN (650 3650) BN 2
J 2
(700 3660);
DISPLAY 0.617021 (700 3660);
PAINT PINK (700 3660);
FORCEPROP 2 LAST CDS_LIB mstr_standard
J 0
(700 3650);
DISPLAY 0.787234 (700 3650);
PAINT MONO (700 3650);
DISPLAY INVISIBLE (700 3650);
FORCEPROP 1 LAST BODY_TYPE PLUMBING
J 2
(700 3600);
DISPLAY 1.234043 (700 3600);
PAINT GREEN (700 3600);
DISPLAY INVISIBLE (700 3600);
FORCEPROP 1 LAST HDL_TAP TRUE
J 2
(375 3525);
DISPLAY 1.234043 (375 3525);
PAINT GREEN (375 3525);
DISPLAY INVISIBLE (375 3525);
FORCEPROP 1 LAST PATH I37
J 2
(700 3650);
DISPLAY 0.936170 (700 3650);
PAINT GREEN (700 3650);
DISPLAY INVISIBLE (700 3650);
FORCEADD TAP..6
R 2
(700 3550);
FORCEPROP 3 LASTPIN (650 3550) SIG_NAME M_E_DQS_DP<1>
J 0
(660 3560);
DISPLAY 0.659574 (660 3560);
PAINT MONO (660 3560);
DISPLAY INVISIBLE (660 3560);
FORCEPROP 1 LASTPIN (650 3550) BN 1
J 2
(700 3560);
DISPLAY 0.617021 (700 3560);
PAINT PINK (700 3560);
FORCEPROP 2 LAST CDS_LIB mstr_standard
J 0
(700 3550);
DISPLAY 0.787234 (700 3550);
PAINT MONO (700 3550);
DISPLAY INVISIBLE (700 3550);
FORCEPROP 1 LAST BODY_TYPE PLUMBING
J 2
(700 3500);
DISPLAY 1.234043 (700 3500);
PAINT GREEN (700 3500);
DISPLAY INVISIBLE (700 3500);
FORCEPROP 1 LAST HDL_TAP TRUE
J 2
(375 3425);
DISPLAY 1.234043 (375 3425);
PAINT GREEN (375 3425);
DISPLAY INVISIBLE (375 3425);
FORCEPROP 1 LAST PATH I38
J 2
(700 3550);
DISPLAY 0.936170 (700 3550);
PAINT GREEN (700 3550);
DISPLAY INVISIBLE (700 3550);
FORCEADD TAP..6
R 2
(900 3400);
FORCEPROP 3 LASTPIN (850 3400) SIG_NAME M_E_DQS_DN<0>
J 0
(860 3410);
DISPLAY 0.659574 (860 3410);
PAINT MONO (860 3410);
DISPLAY INVISIBLE (860 3410);
FORCEPROP 1 LASTPIN (850 3400) BN 0
J 2
(900 3410);
DISPLAY 0.617021 (900 3410);
PAINT PINK (900 3410);
FORCEPROP 2 LAST CDS_LIB mstr_standard
J 0
(900 3400);
DISPLAY 0.787234 (900 3400);
PAINT MONO (900 3400);
DISPLAY INVISIBLE (900 3400);
FORCEPROP 1 LAST BODY_TYPE PLUMBING
J 2
(900 3350);
DISPLAY 1.234043 (900 3350);
PAINT GREEN (900 3350);
DISPLAY INVISIBLE (900 3350);
FORCEPROP 1 LAST HDL_TAP TRUE
J 2
(575 3275);
DISPLAY 1.234043 (575 3275);
PAINT GREEN (575 3275);
DISPLAY INVISIBLE (575 3275);
FORCEPROP 1 LAST PATH I39
J 2
(900 3400);
DISPLAY 0.936170 (900 3400);
PAINT GREEN (900 3400);
DISPLAY INVISIBLE (900 3400);
FORCEADD TAP..6
R 2
(700 5150);
FORCEPROP 3 LASTPIN (650 5150) SIG_NAME M_E_DQS_DP<17>
J 0
(660 5160);
DISPLAY 0.659574 (660 5160);
PAINT MONO (660 5160);
DISPLAY INVISIBLE (660 5160);
FORCEPROP 1 LASTPIN (650 5150) BN 17
J 2
(700 5160);
DISPLAY 0.617021 (700 5160);
PAINT PINK (700 5160);
FORCEPROP 2 LAST CDS_LIB mstr_standard
J 2
(700 5150);
DISPLAY 0.787234 (700 5150);
PAINT MONO (700 5150);
DISPLAY INVISIBLE (700 5150);
FORCEPROP 1 LAST BODY_TYPE PLUMBING
J 2
(700 5100);
DISPLAY 1.234043 (700 5100);
PAINT GREEN (700 5100);
DISPLAY INVISIBLE (700 5100);
FORCEPROP 1 LAST HDL_TAP TRUE
J 2
(375 5025);
DISPLAY 1.234043 (375 5025);
PAINT GREEN (375 5025);
DISPLAY INVISIBLE (375 5025);
FORCEPROP 1 LAST PATH I4
J 2
(700 5150);
DISPLAY 0.936170 (700 5150);
PAINT GREEN (700 5150);
DISPLAY INVISIBLE (700 5150);
FORCEADD TAP..6
R 2
(900 3500);
FORCEPROP 3 LASTPIN (850 3500) SIG_NAME M_E_DQS_DN<1>
J 0
(860 3510);
DISPLAY 0.659574 (860 3510);
PAINT MONO (860 3510);
DISPLAY INVISIBLE (860 3510);
FORCEPROP 1 LASTPIN (850 3500) BN 1
J 2
(900 3510);
DISPLAY 0.617021 (900 3510);
PAINT PINK (900 3510);
FORCEPROP 2 LAST CDS_LIB mstr_standard
J 0
(900 3500);
DISPLAY 0.787234 (900 3500);
PAINT MONO (900 3500);
DISPLAY INVISIBLE (900 3500);
FORCEPROP 1 LAST BODY_TYPE PLUMBING
J 2
(900 3450);
DISPLAY 1.234043 (900 3450);
PAINT GREEN (900 3450);
DISPLAY INVISIBLE (900 3450);
FORCEPROP 1 LAST HDL_TAP TRUE
J 2
(575 3375);
DISPLAY 1.234043 (575 3375);
PAINT GREEN (575 3375);
DISPLAY INVISIBLE (575 3375);
FORCEPROP 1 LAST PATH I40
J 2
(900 3500);
DISPLAY 0.936170 (900 3500);
PAINT GREEN (900 3500);
DISPLAY INVISIBLE (900 3500);
FORCEADD TAP..6
R 2
(700 3450);
FORCEPROP 3 LASTPIN (650 3450) SIG_NAME M_E_DQS_DP<0>
J 0
(660 3460);
DISPLAY 0.659574 (660 3460);
PAINT MONO (660 3460);
DISPLAY INVISIBLE (660 3460);
FORCEPROP 1 LASTPIN (650 3450) BN 0
J 2
(700 3460);
DISPLAY 0.617021 (700 3460);
PAINT PINK (700 3460);
FORCEPROP 2 LAST CDS_LIB mstr_standard
J 0
(700 3450);
DISPLAY 0.787234 (700 3450);
PAINT MONO (700 3450);
DISPLAY INVISIBLE (700 3450);
FORCEPROP 1 LAST BODY_TYPE PLUMBING
J 2
(700 3400);
DISPLAY 1.234043 (700 3400);
PAINT GREEN (700 3400);
DISPLAY INVISIBLE (700 3400);
FORCEPROP 1 LAST HDL_TAP TRUE
J 2
(375 3325);
DISPLAY 1.234043 (375 3325);
PAINT GREEN (375 3325);
DISPLAY INVISIBLE (375 3325);
FORCEPROP 1 LAST PATH I41
J 2
(700 3450);
DISPLAY 0.936170 (700 3450);
PAINT GREEN (700 3450);
DISPLAY INVISIBLE (700 3450);
FORCEADD SCONN288_H44441004..3
(1800 2500);
FORCEPROP 1 LAST PART_NUMBER H44441-004
J 0
(1350 1150);
DISPLAY 0.617021 (1350 1150);
PAINT BLUE (1350 1150);
FORCEPROP 1 LAST MATERIAL SCONN
J 0
(1350 3850);
DISPLAY 0.617021 (1350 3850);
PAINT SKYBLUE (1350 3850);
FORCEPROP 2 LASTPIN (1300 3650) $PN 2
J 2
(1290 3660);
DISPLAY 0.617021 (1290 3660);
PAINT ORANGE (1290 3660);
FORCEPROP 2 LASTPIN (1300 3600) $PN 4
J 2
(1290 3610);
DISPLAY 0.617021 (1290 3610);
PAINT ORANGE (1290 3610);
FORCEPROP 2 LASTPIN (1300 3550) $PN 6
J 2
(1290 3560);
DISPLAY 0.617021 (1290 3560);
PAINT ORANGE (1290 3560);
FORCEPROP 2 LASTPIN (1300 3500) $PN 9
J 2
(1290 3510);
DISPLAY 0.617021 (1290 3510);
PAINT ORANGE (1290 3510);
FORCEPROP 2 LASTPIN (1300 3450) $PN 11
J 2
(1290 3460);
DISPLAY 0.617021 (1290 3460);
PAINT ORANGE (1290 3460);
FORCEPROP 2 LASTPIN (1300 3400) $PN 13
J 2
(1290 3410);
DISPLAY 0.617021 (1290 3410);
PAINT ORANGE (1290 3410);
FORCEPROP 2 LASTPIN (1300 3350) $PN 15
J 2
(1290 3360);
DISPLAY 0.617021 (1290 3360);
PAINT ORANGE (1290 3360);
FORCEPROP 2 LASTPIN (1300 3300) $PN 17
J 2
(1290 3310);
DISPLAY 0.617021 (1290 3310);
PAINT ORANGE (1290 3310);
FORCEPROP 2 LASTPIN (1300 3250) $PN 20
J 2
(1290 3260);
DISPLAY 0.617021 (1290 3260);
PAINT ORANGE (1290 3260);
FORCEPROP 2 LASTPIN (1300 3200) $PN 22
J 2
(1290 3210);
DISPLAY 0.617021 (1290 3210);
PAINT ORANGE (1290 3210);
FORCEPROP 2 LASTPIN (1300 3150) $PN 24
J 2
(1290 3160);
DISPLAY 0.617021 (1290 3160);
PAINT ORANGE (1290 3160);
FORCEPROP 2 LASTPIN (1300 3100) $PN 26
J 2
(1290 3110);
DISPLAY 0.617021 (1290 3110);
PAINT ORANGE (1290 3110);
FORCEPROP 2 LASTPIN (1300 3050) $PN 28
J 2
(1290 3060);
DISPLAY 0.617021 (1290 3060);
PAINT ORANGE (1290 3060);
FORCEPROP 2 LASTPIN (1300 3000) $PN 31
J 2
(1290 3010);
DISPLAY 0.617021 (1290 3010);
PAINT ORANGE (1290 3010);
FORCEPROP 2 LASTPIN (1300 2950) $PN 33
J 2
(1290 2960);
DISPLAY 0.617021 (1290 2960);
PAINT ORANGE (1290 2960);
FORCEPROP 2 LASTPIN (1300 2900) $PN 35
J 2
(1290 2910);
DISPLAY 0.617021 (1290 2910);
PAINT ORANGE (1290 2910);
FORCEPROP 2 LASTPIN (1300 2850) $PN 37
J 2
(1290 2860);
DISPLAY 0.617021 (1290 2860);
PAINT ORANGE (1290 2860);
FORCEPROP 2 LASTPIN (1300 2800) $PN 39
J 2
(1290 2810);
DISPLAY 0.617021 (1290 2810);
PAINT ORANGE (1290 2810);
FORCEPROP 2 LASTPIN (1300 2750) $PN 42
J 2
(1290 2760);
DISPLAY 0.617021 (1290 2760);
PAINT ORANGE (1290 2760);
FORCEPROP 2 LASTPIN (1300 2700) $PN 44
J 2
(1290 2710);
DISPLAY 0.617021 (1290 2710);
PAINT ORANGE (1290 2710);
FORCEPROP 2 LASTPIN (1300 2650) $PN 46
J 2
(1290 2660);
DISPLAY 0.617021 (1290 2660);
PAINT ORANGE (1290 2660);
FORCEPROP 2 LASTPIN (1300 2600) $PN 48
J 2
(1290 2610);
DISPLAY 0.617021 (1290 2610);
PAINT ORANGE (1290 2610);
FORCEPROP 2 LASTPIN (1300 2550) $PN 50
J 2
(1290 2560);
DISPLAY 0.617021 (1290 2560);
PAINT ORANGE (1290 2560);
FORCEPROP 2 LASTPIN (1300 2500) $PN 53
J 2
(1290 2510);
DISPLAY 0.617021 (1290 2510);
PAINT ORANGE (1290 2510);
FORCEPROP 2 LASTPIN (1300 2450) $PN 55
J 2
(1290 2460);
DISPLAY 0.617021 (1290 2460);
PAINT ORANGE (1290 2460);
FORCEPROP 2 LASTPIN (1300 2400) $PN 57
J 2
(1290 2410);
DISPLAY 0.617021 (1290 2410);
PAINT ORANGE (1290 2410);
FORCEPROP 2 LASTPIN (1300 2350) $PN 94
J 2
(1290 2360);
DISPLAY 0.617021 (1290 2360);
PAINT ORANGE (1290 2360);
FORCEPROP 2 LASTPIN (1300 2300) $PN 96
J 2
(1290 2310);
DISPLAY 0.617021 (1290 2310);
PAINT ORANGE (1290 2310);
FORCEPROP 2 LASTPIN (1300 2250) $PN 98
J 2
(1290 2260);
DISPLAY 0.617021 (1290 2260);
PAINT ORANGE (1290 2260);
FORCEPROP 2 LASTPIN (1300 2200) $PN 101
J 2
(1290 2210);
DISPLAY 0.617021 (1290 2210);
PAINT ORANGE (1290 2210);
FORCEPROP 2 LASTPIN (1300 2150) $PN 103
J 2
(1290 2160);
DISPLAY 0.617021 (1290 2160);
PAINT ORANGE (1290 2160);
FORCEPROP 2 LASTPIN (1300 2100) $PN 105
J 2
(1290 2110);
DISPLAY 0.617021 (1290 2110);
PAINT ORANGE (1290 2110);
FORCEPROP 2 LASTPIN (1300 2050) $PN 107
J 2
(1290 2060);
DISPLAY 0.617021 (1290 2060);
PAINT ORANGE (1290 2060);
FORCEPROP 2 LASTPIN (1300 2000) $PN 109
J 2
(1290 2010);
DISPLAY 0.617021 (1290 2010);
PAINT ORANGE (1290 2010);
FORCEPROP 2 LASTPIN (1300 1900) $PN 114
J 2
(1290 1910);
DISPLAY 0.617021 (1290 1910);
PAINT ORANGE (1290 1910);
FORCEPROP 2 LASTPIN (1300 1850) $PN 116
J 2
(1290 1860);
DISPLAY 0.617021 (1290 1860);
PAINT ORANGE (1290 1860);
FORCEPROP 2 LASTPIN (1300 1800) $PN 118
J 2
(1290 1810);
DISPLAY 0.617021 (1290 1810);
PAINT ORANGE (1290 1810);
FORCEPROP 2 LASTPIN (1300 1750) $PN 120
J 2
(1290 1760);
DISPLAY 0.617021 (1290 1760);
PAINT ORANGE (1290 1760);
FORCEPROP 2 LASTPIN (1300 1700) $PN 123
J 2
(1290 1710);
DISPLAY 0.617021 (1290 1710);
PAINT ORANGE (1290 1710);
FORCEPROP 2 LASTPIN (1300 1650) $PN 125
J 2
(1290 1660);
DISPLAY 0.617021 (1290 1660);
PAINT ORANGE (1290 1660);
FORCEPROP 2 LASTPIN (1300 1600) $PN 127
J 2
(1290 1610);
DISPLAY 0.617021 (1290 1610);
PAINT ORANGE (1290 1610);
FORCEPROP 2 LASTPIN (1300 1550) $PN 129
J 2
(1290 1560);
DISPLAY 0.617021 (1290 1560);
PAINT ORANGE (1290 1560);
FORCEPROP 2 LASTPIN (1300 1450) $PN 134
J 2
(1290 1460);
DISPLAY 0.617021 (1290 1460);
PAINT ORANGE (1290 1460);
FORCEPROP 2 LASTPIN (1300 1400) $PN 136
J 2
(1290 1410);
DISPLAY 0.617021 (1290 1410);
PAINT ORANGE (1290 1410);
FORCEPROP 2 LASTPIN (1300 1350) $PN 138
J 2
(1290 1360);
DISPLAY 0.617021 (1290 1360);
PAINT ORANGE (1290 1360);
FORCEPROP 2 LASTPIN (2300 3650) $PN 147
J 0
(2310 3660);
DISPLAY 0.617021 (2310 3660);
PAINT ORANGE (2310 3660);
FORCEPROP 2 LASTPIN (2300 3600) $PN 149
J 0
(2310 3610);
DISPLAY 0.617021 (2310 3610);
PAINT ORANGE (2310 3610);
FORCEPROP 2 LASTPIN (2300 3550) $PN 151
J 0
(2310 3560);
DISPLAY 0.617021 (2310 3560);
PAINT ORANGE (2310 3560);
FORCEPROP 2 LASTPIN (2300 3500) $PN 154
J 0
(2310 3510);
DISPLAY 0.617021 (2310 3510);
PAINT ORANGE (2310 3510);
FORCEPROP 2 LASTPIN (2300 3450) $PN 156
J 0
(2310 3460);
DISPLAY 0.617021 (2310 3460);
PAINT ORANGE (2310 3460);
FORCEPROP 2 LASTPIN (2300 3400) $PN 158
J 0
(2310 3410);
DISPLAY 0.617021 (2310 3410);
PAINT ORANGE (2310 3410);
FORCEPROP 2 LASTPIN (2300 3350) $PN 160
J 0
(2310 3360);
DISPLAY 0.617021 (2310 3360);
PAINT ORANGE (2310 3360);
FORCEPROP 2 LASTPIN (2300 3300) $PN 162
J 0
(2310 3310);
DISPLAY 0.617021 (2310 3310);
PAINT ORANGE (2310 3310);
FORCEPROP 2 LASTPIN (2300 3250) $PN 165
J 0
(2310 3260);
DISPLAY 0.617021 (2310 3260);
PAINT ORANGE (2310 3260);
FORCEPROP 2 LASTPIN (2300 3200) $PN 167
J 0
(2310 3210);
DISPLAY 0.617021 (2310 3210);
PAINT ORANGE (2310 3210);
FORCEPROP 2 LASTPIN (2300 3150) $PN 169
J 0
(2310 3160);
DISPLAY 0.617021 (2310 3160);
PAINT ORANGE (2310 3160);
FORCEPROP 2 LASTPIN (2300 3100) $PN 171
J 0
(2310 3110);
DISPLAY 0.617021 (2310 3110);
PAINT ORANGE (2310 3110);
FORCEPROP 2 LASTPIN (2300 3050) $PN 173
J 0
(2310 3060);
DISPLAY 0.617021 (2310 3060);
PAINT ORANGE (2310 3060);
FORCEPROP 2 LASTPIN (2300 3000) $PN 176
J 0
(2310 3010);
DISPLAY 0.617021 (2310 3010);
PAINT ORANGE (2310 3010);
FORCEPROP 2 LASTPIN (2300 2950) $PN 178
J 0
(2310 2960);
DISPLAY 0.617021 (2310 2960);
PAINT ORANGE (2310 2960);
FORCEPROP 2 LASTPIN (2300 2900) $PN 180
J 0
(2310 2910);
DISPLAY 0.617021 (2310 2910);
PAINT ORANGE (2310 2910);
FORCEPROP 2 LASTPIN (2300 2850) $PN 182
J 0
(2310 2860);
DISPLAY 0.617021 (2310 2860);
PAINT ORANGE (2310 2860);
FORCEPROP 2 LASTPIN (2300 2800) $PN 184
J 0
(2310 2810);
DISPLAY 0.617021 (2310 2810);
PAINT ORANGE (2310 2810);
FORCEPROP 2 LASTPIN (2300 2750) $PN 187
J 0
(2310 2760);
DISPLAY 0.617021 (2310 2760);
PAINT ORANGE (2310 2760);
FORCEPROP 2 LASTPIN (2300 2700) $PN 189
J 0
(2310 2710);
DISPLAY 0.617021 (2310 2710);
PAINT ORANGE (2310 2710);
FORCEPROP 2 LASTPIN (2300 2650) $PN 191
J 0
(2310 2660);
DISPLAY 0.617021 (2310 2660);
PAINT ORANGE (2310 2660);
FORCEPROP 2 LASTPIN (2300 2600) $PN 193
J 0
(2310 2610);
DISPLAY 0.617021 (2310 2610);
PAINT ORANGE (2310 2610);
FORCEPROP 2 LASTPIN (2300 2550) $PN 195
J 0
(2310 2560);
DISPLAY 0.617021 (2310 2560);
PAINT ORANGE (2310 2560);
FORCEPROP 2 LASTPIN (2300 2500) $PN 198
J 0
(2310 2510);
DISPLAY 0.617021 (2310 2510);
PAINT ORANGE (2310 2510);
FORCEPROP 2 LASTPIN (2300 2450) $PN 200
J 0
(2310 2460);
DISPLAY 0.617021 (2310 2460);
PAINT ORANGE (2310 2460);
FORCEPROP 2 LASTPIN (2300 2400) $PN 202
J 0
(2310 2410);
DISPLAY 0.617021 (2310 2410);
PAINT ORANGE (2310 2410);
FORCEPROP 2 LASTPIN (2300 2350) $PN 239
J 0
(2310 2360);
DISPLAY 0.617021 (2310 2360);
PAINT ORANGE (2310 2360);
FORCEPROP 2 LASTPIN (2300 2300) $PN 241
J 0
(2310 2310);
DISPLAY 0.617021 (2310 2310);
PAINT ORANGE (2310 2310);
FORCEPROP 2 LASTPIN (2300 2250) $PN 243
J 0
(2310 2260);
DISPLAY 0.617021 (2310 2260);
PAINT ORANGE (2310 2260);
FORCEPROP 2 LASTPIN (2300 2200) $PN 246
J 0
(2310 2210);
DISPLAY 0.617021 (2310 2210);
PAINT ORANGE (2310 2210);
FORCEPROP 2 LASTPIN (2300 2150) $PN 248
J 0
(2310 2160);
DISPLAY 0.617021 (2310 2160);
PAINT ORANGE (2310 2160);
FORCEPROP 2 LASTPIN (2300 2100) $PN 250
J 0
(2310 2110);
DISPLAY 0.617021 (2310 2110);
PAINT ORANGE (2310 2110);
FORCEPROP 2 LASTPIN (2300 2050) $PN 252
J 0
(2310 2060);
DISPLAY 0.617021 (2310 2060);
PAINT ORANGE (2310 2060);
FORCEPROP 2 LASTPIN (2300 2000) $PN 254
J 0
(2310 2010);
DISPLAY 0.617021 (2310 2010);
PAINT ORANGE (2310 2010);
FORCEPROP 2 LASTPIN (2300 1950) $PN 257
J 0
(2310 1960);
DISPLAY 0.617021 (2310 1960);
PAINT ORANGE (2310 1960);
FORCEPROP 2 LASTPIN (2300 1900) $PN 259
J 0
(2310 1910);
DISPLAY 0.617021 (2310 1910);
PAINT ORANGE (2310 1910);
FORCEPROP 2 LASTPIN (2300 1850) $PN 261
J 0
(2310 1860);
DISPLAY 0.617021 (2310 1860);
PAINT ORANGE (2310 1860);
FORCEPROP 2 LASTPIN (2300 1800) $PN 263
J 0
(2310 1810);
DISPLAY 0.617021 (2310 1810);
PAINT ORANGE (2310 1810);
FORCEPROP 2 LASTPIN (2300 1750) $PN 265
J 0
(2310 1760);
DISPLAY 0.617021 (2310 1760);
PAINT ORANGE (2310 1760);
FORCEPROP 2 LASTPIN (2300 1700) $PN 268
J 0
(2310 1710);
DISPLAY 0.617021 (2310 1710);
PAINT ORANGE (2310 1710);
FORCEPROP 2 LASTPIN (2300 1650) $PN 270
J 0
(2310 1660);
DISPLAY 0.617021 (2310 1660);
PAINT ORANGE (2310 1660);
FORCEPROP 2 LASTPIN (2300 1600) $PN 272
J 0
(2310 1610);
DISPLAY 0.617021 (2310 1610);
PAINT ORANGE (2310 1610);
FORCEPROP 2 LASTPIN (2300 1550) $PN 274
J 0
(2310 1560);
DISPLAY 0.617021 (2310 1560);
PAINT ORANGE (2310 1560);
FORCEPROP 2 LASTPIN (2300 1500) $PN 276
J 0
(2310 1510);
DISPLAY 0.617021 (2310 1510);
PAINT ORANGE (2310 1510);
FORCEPROP 2 LASTPIN (2300 1450) $PN 279
J 0
(2310 1460);
DISPLAY 0.617021 (2310 1460);
PAINT ORANGE (2310 1460);
FORCEPROP 2 LASTPIN (2300 1400) $PN 281
J 0
(2310 1410);
DISPLAY 0.617021 (2310 1410);
PAINT ORANGE (2310 1410);
FORCEPROP 2 LASTPIN (2300 1350) $PN 283
J 0
(2310 1360);
DISPLAY 0.617021 (2310 1360);
PAINT ORANGE (2310 1360);
FORCEPROP 1 LAST LOCATION J4A2
J 0
(1350 3900);
DISPLAY 0.617021 (1350 3900);
PAINT AQUA (1350 3900);
FORCEPROP 2 LASTPIN (1300 1950) $PN 112
J 2
(1290 1960);
DISPLAY 0.617021 (1290 1960);
PAINT ORANGE (1290 1960);
FORCEPROP 2 LASTPIN (1300 1500) $PN 131
J 2
(1290 1510);
DISPLAY 0.617021 (1290 1510);
PAINT ORANGE (1290 1510);
FORCEPROP 1 LAST PACK_TYPE PIP
J 0
(1350 3950);
PAINT SKYBLUE (1350 3950);
DISPLAY INVISIBLE (1350 3950);
FORCEPROP 2 LAST BOM_COST MEM
J 0
(1800 2500);
PAINT ORANGE (1800 2500);
DISPLAY INVISIBLE (1800 2500);
FORCEPROP 2 LAST CDS_LIB mstr_sconn
J 0
(1800 2500);
PAINT ORANGE (1800 2500);
DISPLAY INVISIBLE (1800 2500);
FORCEPROP 2 LAST SEC_TYPE PIP
J 0
(1350 3950);
DISPLAY 1.021277 (1350 3950);
PAINT ORANGE (1350 3950);
DISPLAY INVISIBLE (1350 3950);
FORCEPROP 2 LAST SEC 3
J 0
(1350 3950);
DISPLAY 0.680851 (1350 3950);
PAINT MONO (1350 3950);
DISPLAY INVISIBLE (1350 3950);
FORCEPROP 2 LAST CDS_LOCATION J4A2
J 0
(1350 3900);
DISPLAY 0.617021 (1350 3900);
PAINT AQUA (1350 3900);
DISPLAY INVISIBLE (1350 3900);
FORCEPROP 1 LAST PATH I43
J 0
(1800 3850);
PAINT GREEN (1800 3850);
DISPLAY INVISIBLE (1800 3850);
FORCEPROP 2 LAST ROOM DDR4_CH_E
J 0
(1800 2500);
PAINT ORANGE (1800 2500);
DISPLAY INVISIBLE (1800 2500);
FORCEADD GND..1
R 2
(1100 1200);
FORCEPROP 3 LASTPIN (1100 1250) SIG_NAME GND\g
J 0
(1110 1260);
DISPLAY 0.659574 (1110 1260);
PAINT MONO (1110 1260);
DISPLAY INVISIBLE (1110 1260);
FORCEPROP 1 LAST VOLTAGE 0
J 0
(1100 1200);
PAINT SKYBLUE (1100 1200);
DISPLAY INVISIBLE (1100 1200);
FORCEPROP 1 LAST SIZE 1B
J 2
(1025 1150);
DISPLAY 1.170213 (1025 1150);
PAINT GREEN (1025 1150);
DISPLAY INVISIBLE (1025 1150);
FORCEPROP 2 LAST CDS_LIB mstr_symbols
J 0
(1100 1200);
DISPLAY 0.787234 (1100 1200);
PAINT MONO (1100 1200);
DISPLAY INVISIBLE (1100 1200);
FORCEPROP 2 LAST BOM_COST MEM
J 0
(1100 1205);
PAINT ORANGE (1100 1205);
DISPLAY INVISIBLE (1100 1205);
FORCEPROP 1 LAST BODY_TYPE PLUMBING
J 2
(1145 1157);
DISPLAY 0.340426 (1145 1157);
PAINT GREEN (1145 1157);
DISPLAY INVISIBLE (1145 1157);
FORCEPROP 1 LAST PATH I44
J 2
(1025 1200);
DISPLAY 0.936170 (1025 1200);
PAINT GREEN (1025 1200);
DISPLAY INVISIBLE (1025 1200);
FORCEPROP 2 LAST ROOM DDR4_CH_B
J 0
(1100 1205);
PAINT ORANGE (1100 1205);
DISPLAY INVISIBLE (1100 1205);
FORCEPROP 1 LAST HDL_POWER GND
J 2
(1100 1350);
DISPLAY 0.553191 (1100 1350);
PAINT GREEN (1100 1350);
DISPLAY INVISIBLE (1100 1350);
FORCEADD OFFPAGE..3
(-1050 4950);
FORCEPROP 2 LAST $XR1 52 
J 0
(-746 4950);
DISPLAY 0.638298 (-746 4950);
PAINT MONO (-746 4950);
FORCEPROP 2 LAST $XR0 27 
J 0
(-836 4950);
DISPLAY 0.638298 (-836 4950);
PAINT MONO (-836 4950);
FORCEPROP 2 LAST CDS_LIB mstr_standard
J 0
(-1050 4950);
DISPLAY 0.787234 (-1050 4950);
PAINT MONO (-1050 4950);
DISPLAY INVISIBLE (-1050 4950);
FORCEPROP 1 LAST OFFPAGE TRUE
J 0
(-725 4825);
DISPLAY 0.936170 (-725 4825);
PAINT GREEN (-725 4825);
DISPLAY INVISIBLE (-725 4825);
FORCEPROP 1 LAST COMMENT_BODY TRUE
J 0
(-1100 4850);
DISPLAY 0.936170 (-1100 4850);
PAINT GREEN (-1100 4850);
DISPLAY INVISIBLE (-1100 4850);
FORCEPROP 2 LAST PATH I45
J 0
(-850 5025);
DISPLAY 0.787234 (-850 5025);
PAINT MONO (-850 5025);
DISPLAY INVISIBLE (-850 5025);
FORCEADD TAP..6
R 2
(-1600 4900);
FORCEPROP 3 LASTPIN (-1650 4900) SIG_NAME M_E_DQ<62>
J 0
(-1640 4910);
DISPLAY 0.659574 (-1640 4910);
PAINT MONO (-1640 4910);
DISPLAY INVISIBLE (-1640 4910);
FORCEPROP 1 LASTPIN (-1650 4900) BN 62
J 2
(-1600 4910);
DISPLAY 0.617021 (-1600 4910);
PAINT PINK (-1600 4910);
FORCEPROP 2 LAST CDS_LIB mstr_standard
J 2
(-1600 4900);
DISPLAY 0.787234 (-1600 4900);
PAINT MONO (-1600 4900);
DISPLAY INVISIBLE (-1600 4900);
FORCEPROP 1 LAST BODY_TYPE PLUMBING
J 2
(-1600 4850);
DISPLAY 1.234043 (-1600 4850);
PAINT GREEN (-1600 4850);
DISPLAY INVISIBLE (-1600 4850);
FORCEPROP 1 LAST HDL_TAP TRUE
J 2
(-1925 4775);
DISPLAY 1.234043 (-1925 4775);
PAINT GREEN (-1925 4775);
DISPLAY INVISIBLE (-1925 4775);
FORCEPROP 1 LAST PATH I46
J 2
(-1600 4900);
DISPLAY 0.936170 (-1600 4900);
PAINT GREEN (-1600 4900);
DISPLAY INVISIBLE (-1600 4900);
FORCEADD TAP..6
R 2
(-1600 4850);
FORCEPROP 3 LASTPIN (-1650 4850) SIG_NAME M_E_DQ<63>
J 0
(-1640 4860);
DISPLAY 0.659574 (-1640 4860);
PAINT MONO (-1640 4860);
DISPLAY INVISIBLE (-1640 4860);
FORCEPROP 1 LASTPIN (-1650 4850) BN 63
J 2
(-1600 4860);
DISPLAY 0.617021 (-1600 4860);
PAINT PINK (-1600 4860);
FORCEPROP 2 LAST CDS_LIB mstr_standard
J 2
(-1600 4850);
DISPLAY 0.787234 (-1600 4850);
PAINT MONO (-1600 4850);
DISPLAY INVISIBLE (-1600 4850);
FORCEPROP 1 LAST BODY_TYPE PLUMBING
J 2
(-1600 4800);
DISPLAY 1.234043 (-1600 4800);
PAINT GREEN (-1600 4800);
DISPLAY INVISIBLE (-1600 4800);
FORCEPROP 1 LAST HDL_TAP TRUE
J 2
(-1925 4725);
DISPLAY 1.234043 (-1925 4725);
PAINT GREEN (-1925 4725);
DISPLAY INVISIBLE (-1925 4725);
FORCEPROP 1 LAST PATH I47
J 2
(-1600 4850);
DISPLAY 0.936170 (-1600 4850);
PAINT GREEN (-1600 4850);
DISPLAY INVISIBLE (-1600 4850);
FORCEADD TAP..6
R 2
(-1600 4750);
FORCEPROP 3 LASTPIN (-1650 4750) SIG_NAME M_E_DQ<61>
J 0
(-1640 4760);
DISPLAY 0.659574 (-1640 4760);
PAINT MONO (-1640 4760);
DISPLAY INVISIBLE (-1640 4760);
FORCEPROP 1 LASTPIN (-1650 4750) BN 61
J 2
(-1600 4760);
DISPLAY 0.617021 (-1600 4760);
PAINT PINK (-1600 4760);
FORCEPROP 2 LAST CDS_LIB mstr_standard
J 2
(-1600 4750);
DISPLAY 0.787234 (-1600 4750);
PAINT MONO (-1600 4750);
DISPLAY INVISIBLE (-1600 4750);
FORCEPROP 1 LAST BODY_TYPE PLUMBING
J 2
(-1600 4700);
DISPLAY 1.234043 (-1600 4700);
PAINT GREEN (-1600 4700);
DISPLAY INVISIBLE (-1600 4700);
FORCEPROP 1 LAST HDL_TAP TRUE
J 2
(-1925 4625);
DISPLAY 1.234043 (-1925 4625);
PAINT GREEN (-1925 4625);
DISPLAY INVISIBLE (-1925 4625);
FORCEPROP 1 LAST PATH I48
J 2
(-1600 4750);
DISPLAY 0.936170 (-1600 4750);
PAINT GREEN (-1600 4750);
DISPLAY INVISIBLE (-1600 4750);
FORCEADD TAP..6
R 2
(-1600 4800);
FORCEPROP 3 LASTPIN (-1650 4800) SIG_NAME M_E_DQ<60>
J 0
(-1640 4810);
DISPLAY 0.659574 (-1640 4810);
PAINT MONO (-1640 4810);
DISPLAY INVISIBLE (-1640 4810);
FORCEPROP 1 LASTPIN (-1650 4800) BN 60
J 2
(-1600 4810);
DISPLAY 0.617021 (-1600 4810);
PAINT PINK (-1600 4810);
FORCEPROP 2 LAST CDS_LIB mstr_standard
J 2
(-1600 4800);
DISPLAY 0.787234 (-1600 4800);
PAINT MONO (-1600 4800);
DISPLAY INVISIBLE (-1600 4800);
FORCEPROP 1 LAST BODY_TYPE PLUMBING
J 2
(-1600 4750);
DISPLAY 1.234043 (-1600 4750);
PAINT GREEN (-1600 4750);
DISPLAY INVISIBLE (-1600 4750);
FORCEPROP 1 LAST HDL_TAP TRUE
J 2
(-1925 4675);
DISPLAY 1.234043 (-1925 4675);
PAINT GREEN (-1925 4675);
DISPLAY INVISIBLE (-1925 4675);
FORCEPROP 1 LAST PATH I49
J 2
(-1600 4800);
DISPLAY 0.936170 (-1600 4800);
PAINT GREEN (-1600 4800);
DISPLAY INVISIBLE (-1600 4800);
FORCEADD TAP..6
R 2
(900 5000);
FORCEPROP 3 LASTPIN (850 5000) SIG_NAME M_E_DQS_DN<16>
J 0
(860 5010);
DISPLAY 0.659574 (860 5010);
PAINT MONO (860 5010);
DISPLAY INVISIBLE (860 5010);
FORCEPROP 1 LASTPIN (850 5000) BN 16
J 2
(900 5010);
DISPLAY 0.617021 (900 5010);
PAINT PINK (900 5010);
FORCEPROP 2 LAST CDS_LIB mstr_standard
J 0
(900 5000);
DISPLAY 0.787234 (900 5000);
PAINT MONO (900 5000);
DISPLAY INVISIBLE (900 5000);
FORCEPROP 1 LAST BODY_TYPE PLUMBING
J 2
(900 4950);
DISPLAY 1.234043 (900 4950);
PAINT GREEN (900 4950);
DISPLAY INVISIBLE (900 4950);
FORCEPROP 1 LAST HDL_TAP TRUE
J 2
(575 4875);
DISPLAY 1.234043 (575 4875);
PAINT GREEN (575 4875);
DISPLAY INVISIBLE (575 4875);
FORCEPROP 1 LAST PATH I5
J 2
(900 5000);
DISPLAY 0.936170 (900 5000);
PAINT GREEN (900 5000);
DISPLAY INVISIBLE (900 5000);
FORCEADD TAP..6
R 2
(-1600 4700);
FORCEPROP 3 LASTPIN (-1650 4700) SIG_NAME M_E_DQ<58>
J 0
(-1640 4710);
DISPLAY 0.659574 (-1640 4710);
PAINT MONO (-1640 4710);
DISPLAY INVISIBLE (-1640 4710);
FORCEPROP 1 LASTPIN (-1650 4700) BN 58
J 2
(-1600 4710);
DISPLAY 0.617021 (-1600 4710);
PAINT PINK (-1600 4710);
FORCEPROP 2 LAST CDS_LIB mstr_standard
J 2
(-1600 4700);
DISPLAY 0.787234 (-1600 4700);
PAINT MONO (-1600 4700);
DISPLAY INVISIBLE (-1600 4700);
FORCEPROP 1 LAST BODY_TYPE PLUMBING
J 2
(-1600 4650);
DISPLAY 1.234043 (-1600 4650);
PAINT GREEN (-1600 4650);
DISPLAY INVISIBLE (-1600 4650);
FORCEPROP 1 LAST HDL_TAP TRUE
J 2
(-1925 4575);
DISPLAY 1.234043 (-1925 4575);
PAINT GREEN (-1925 4575);
DISPLAY INVISIBLE (-1925 4575);
FORCEPROP 1 LAST PATH I50
J 2
(-1600 4700);
DISPLAY 0.936170 (-1600 4700);
PAINT GREEN (-1600 4700);
DISPLAY INVISIBLE (-1600 4700);
FORCEADD TAP..6
R 2
(-1600 4600);
FORCEPROP 3 LASTPIN (-1650 4600) SIG_NAME M_E_DQ<56>
J 0
(-1640 4610);
DISPLAY 0.659574 (-1640 4610);
PAINT MONO (-1640 4610);
DISPLAY INVISIBLE (-1640 4610);
FORCEPROP 1 LASTPIN (-1650 4600) BN 56
J 2
(-1600 4610);
DISPLAY 0.617021 (-1600 4610);
PAINT PINK (-1600 4610);
FORCEPROP 2 LAST CDS_LIB mstr_standard
J 2
(-1600 4600);
DISPLAY 0.787234 (-1600 4600);
PAINT MONO (-1600 4600);
DISPLAY INVISIBLE (-1600 4600);
FORCEPROP 1 LAST BODY_TYPE PLUMBING
J 2
(-1600 4550);
DISPLAY 1.234043 (-1600 4550);
PAINT GREEN (-1600 4550);
DISPLAY INVISIBLE (-1600 4550);
FORCEPROP 1 LAST HDL_TAP TRUE
J 2
(-1925 4475);
DISPLAY 1.234043 (-1925 4475);
PAINT GREEN (-1925 4475);
DISPLAY INVISIBLE (-1925 4475);
FORCEPROP 1 LAST PATH I51
J 2
(-1600 4600);
DISPLAY 0.936170 (-1600 4600);
PAINT GREEN (-1600 4600);
DISPLAY INVISIBLE (-1600 4600);
FORCEADD TAP..6
R 2
(-1600 4650);
FORCEPROP 3 LASTPIN (-1650 4650) SIG_NAME M_E_DQ<59>
J 0
(-1640 4660);
DISPLAY 0.659574 (-1640 4660);
PAINT MONO (-1640 4660);
DISPLAY INVISIBLE (-1640 4660);
FORCEPROP 1 LASTPIN (-1650 4650) BN 59
J 2
(-1600 4660);
DISPLAY 0.617021 (-1600 4660);
PAINT PINK (-1600 4660);
FORCEPROP 2 LAST CDS_LIB mstr_standard
J 2
(-1600 4650);
DISPLAY 0.787234 (-1600 4650);
PAINT MONO (-1600 4650);
DISPLAY INVISIBLE (-1600 4650);
FORCEPROP 1 LAST BODY_TYPE PLUMBING
J 2
(-1600 4600);
DISPLAY 1.234043 (-1600 4600);
PAINT GREEN (-1600 4600);
DISPLAY INVISIBLE (-1600 4600);
FORCEPROP 1 LAST HDL_TAP TRUE
J 2
(-1925 4525);
DISPLAY 1.234043 (-1925 4525);
PAINT GREEN (-1925 4525);
DISPLAY INVISIBLE (-1925 4525);
FORCEPROP 1 LAST PATH I52
J 2
(-1600 4650);
DISPLAY 0.936170 (-1600 4650);
PAINT GREEN (-1600 4650);
DISPLAY INVISIBLE (-1600 4650);
FORCEADD TAP..6
R 2
(-1600 4550);
FORCEPROP 3 LASTPIN (-1650 4550) SIG_NAME M_E_DQ<57>
J 0
(-1640 4560);
DISPLAY 0.659574 (-1640 4560);
PAINT MONO (-1640 4560);
DISPLAY INVISIBLE (-1640 4560);
FORCEPROP 1 LASTPIN (-1650 4550) BN 57
J 2
(-1600 4560);
DISPLAY 0.617021 (-1600 4560);
PAINT PINK (-1600 4560);
FORCEPROP 2 LAST CDS_LIB mstr_standard
J 2
(-1600 4550);
DISPLAY 0.787234 (-1600 4550);
PAINT MONO (-1600 4550);
DISPLAY INVISIBLE (-1600 4550);
FORCEPROP 1 LAST BODY_TYPE PLUMBING
J 2
(-1600 4500);
DISPLAY 1.234043 (-1600 4500);
PAINT GREEN (-1600 4500);
DISPLAY INVISIBLE (-1600 4500);
FORCEPROP 1 LAST HDL_TAP TRUE
J 2
(-1925 4425);
DISPLAY 1.234043 (-1925 4425);
PAINT GREEN (-1925 4425);
DISPLAY INVISIBLE (-1925 4425);
FORCEPROP 1 LAST PATH I53
J 2
(-1600 4550);
DISPLAY 0.936170 (-1600 4550);
PAINT GREEN (-1600 4550);
DISPLAY INVISIBLE (-1600 4550);
FORCEADD TAP..6
R 2
(-1600 4500);
FORCEPROP 3 LASTPIN (-1650 4500) SIG_NAME M_E_DQ<54>
J 0
(-1640 4510);
DISPLAY 0.659574 (-1640 4510);
PAINT MONO (-1640 4510);
DISPLAY INVISIBLE (-1640 4510);
FORCEPROP 1 LASTPIN (-1650 4500) BN 54
J 2
(-1600 4510);
DISPLAY 0.617021 (-1600 4510);
PAINT PINK (-1600 4510);
FORCEPROP 2 LAST CDS_LIB mstr_standard
J 2
(-1600 4500);
DISPLAY 0.787234 (-1600 4500);
PAINT MONO (-1600 4500);
DISPLAY INVISIBLE (-1600 4500);
FORCEPROP 1 LAST BODY_TYPE PLUMBING
J 2
(-1600 4450);
DISPLAY 1.234043 (-1600 4450);
PAINT GREEN (-1600 4450);
DISPLAY INVISIBLE (-1600 4450);
FORCEPROP 1 LAST HDL_TAP TRUE
J 2
(-1925 4375);
DISPLAY 1.234043 (-1925 4375);
PAINT GREEN (-1925 4375);
DISPLAY INVISIBLE (-1925 4375);
FORCEPROP 1 LAST PATH I54
J 2
(-1600 4500);
DISPLAY 0.936170 (-1600 4500);
PAINT GREEN (-1600 4500);
DISPLAY INVISIBLE (-1600 4500);
FORCEADD TAP..6
R 2
(-1600 4400);
FORCEPROP 3 LASTPIN (-1650 4400) SIG_NAME M_E_DQ<52>
J 0
(-1640 4410);
DISPLAY 0.659574 (-1640 4410);
PAINT MONO (-1640 4410);
DISPLAY INVISIBLE (-1640 4410);
FORCEPROP 1 LASTPIN (-1650 4400) BN 52
J 2
(-1600 4410);
DISPLAY 0.617021 (-1600 4410);
PAINT PINK (-1600 4410);
FORCEPROP 2 LAST CDS_LIB mstr_standard
J 2
(-1600 4400);
DISPLAY 0.787234 (-1600 4400);
PAINT MONO (-1600 4400);
DISPLAY INVISIBLE (-1600 4400);
FORCEPROP 1 LAST BODY_TYPE PLUMBING
J 2
(-1600 4350);
DISPLAY 1.234043 (-1600 4350);
PAINT GREEN (-1600 4350);
DISPLAY INVISIBLE (-1600 4350);
FORCEPROP 1 LAST HDL_TAP TRUE
J 2
(-1925 4275);
DISPLAY 1.234043 (-1925 4275);
PAINT GREEN (-1925 4275);
DISPLAY INVISIBLE (-1925 4275);
FORCEPROP 1 LAST PATH I55
J 2
(-1600 4400);
DISPLAY 0.936170 (-1600 4400);
PAINT GREEN (-1600 4400);
DISPLAY INVISIBLE (-1600 4400);
FORCEADD TAP..6
R 2
(-1600 4450);
FORCEPROP 3 LASTPIN (-1650 4450) SIG_NAME M_E_DQ<55>
J 0
(-1640 4460);
DISPLAY 0.659574 (-1640 4460);
PAINT MONO (-1640 4460);
DISPLAY INVISIBLE (-1640 4460);
FORCEPROP 1 LASTPIN (-1650 4450) BN 55
J 2
(-1600 4460);
DISPLAY 0.617021 (-1600 4460);
PAINT PINK (-1600 4460);
FORCEPROP 2 LAST CDS_LIB mstr_standard
J 2
(-1600 4450);
DISPLAY 0.787234 (-1600 4450);
PAINT MONO (-1600 4450);
DISPLAY INVISIBLE (-1600 4450);
FORCEPROP 1 LAST BODY_TYPE PLUMBING
J 2
(-1600 4400);
DISPLAY 1.234043 (-1600 4400);
PAINT GREEN (-1600 4400);
DISPLAY INVISIBLE (-1600 4400);
FORCEPROP 1 LAST HDL_TAP TRUE
J 2
(-1925 4325);
DISPLAY 1.234043 (-1925 4325);
PAINT GREEN (-1925 4325);
DISPLAY INVISIBLE (-1925 4325);
FORCEPROP 1 LAST PATH I56
J 2
(-1600 4450);
DISPLAY 0.936170 (-1600 4450);
PAINT GREEN (-1600 4450);
DISPLAY INVISIBLE (-1600 4450);
FORCEADD TAP..6
R 2
(-1600 4350);
FORCEPROP 3 LASTPIN (-1650 4350) SIG_NAME M_E_DQ<53>
J 0
(-1640 4360);
DISPLAY 0.659574 (-1640 4360);
PAINT MONO (-1640 4360);
DISPLAY INVISIBLE (-1640 4360);
FORCEPROP 1 LASTPIN (-1650 4350) BN 53
J 2
(-1600 4360);
DISPLAY 0.617021 (-1600 4360);
PAINT PINK (-1600 4360);
FORCEPROP 2 LAST CDS_LIB mstr_standard
J 2
(-1600 4350);
DISPLAY 0.787234 (-1600 4350);
PAINT MONO (-1600 4350);
DISPLAY INVISIBLE (-1600 4350);
FORCEPROP 1 LAST BODY_TYPE PLUMBING
J 2
(-1600 4300);
DISPLAY 1.234043 (-1600 4300);
PAINT GREEN (-1600 4300);
DISPLAY INVISIBLE (-1600 4300);
FORCEPROP 1 LAST HDL_TAP TRUE
J 2
(-1925 4225);
DISPLAY 1.234043 (-1925 4225);
PAINT GREEN (-1925 4225);
DISPLAY INVISIBLE (-1925 4225);
FORCEPROP 1 LAST PATH I57
J 2
(-1600 4350);
DISPLAY 0.936170 (-1600 4350);
PAINT GREEN (-1600 4350);
DISPLAY INVISIBLE (-1600 4350);
FORCEADD TAP..6
R 2
(-1600 4300);
FORCEPROP 3 LASTPIN (-1650 4300) SIG_NAME M_E_DQ<50>
J 0
(-1640 4310);
DISPLAY 0.659574 (-1640 4310);
PAINT MONO (-1640 4310);
DISPLAY INVISIBLE (-1640 4310);
FORCEPROP 1 LASTPIN (-1650 4300) BN 50
J 2
(-1600 4310);
DISPLAY 0.617021 (-1600 4310);
PAINT PINK (-1600 4310);
FORCEPROP 2 LAST CDS_LIB mstr_standard
J 2
(-1600 4300);
DISPLAY 0.787234 (-1600 4300);
PAINT MONO (-1600 4300);
DISPLAY INVISIBLE (-1600 4300);
FORCEPROP 1 LAST BODY_TYPE PLUMBING
J 2
(-1600 4250);
DISPLAY 1.234043 (-1600 4250);
PAINT GREEN (-1600 4250);
DISPLAY INVISIBLE (-1600 4250);
FORCEPROP 1 LAST HDL_TAP TRUE
J 2
(-1925 4175);
DISPLAY 1.234043 (-1925 4175);
PAINT GREEN (-1925 4175);
DISPLAY INVISIBLE (-1925 4175);
FORCEPROP 1 LAST PATH I58
J 2
(-1600 4300);
DISPLAY 0.936170 (-1600 4300);
PAINT GREEN (-1600 4300);
DISPLAY INVISIBLE (-1600 4300);
FORCEADD TAP..6
R 2
(-1600 4250);
FORCEPROP 3 LASTPIN (-1650 4250) SIG_NAME M_E_DQ<51>
J 0
(-1640 4260);
DISPLAY 0.659574 (-1640 4260);
PAINT MONO (-1640 4260);
DISPLAY INVISIBLE (-1640 4260);
FORCEPROP 1 LASTPIN (-1650 4250) BN 51
J 2
(-1600 4260);
DISPLAY 0.617021 (-1600 4260);
PAINT PINK (-1600 4260);
FORCEPROP 2 LAST CDS_LIB mstr_standard
J 2
(-1600 4250);
DISPLAY 0.787234 (-1600 4250);
PAINT MONO (-1600 4250);
DISPLAY INVISIBLE (-1600 4250);
FORCEPROP 1 LAST BODY_TYPE PLUMBING
J 2
(-1600 4200);
DISPLAY 1.234043 (-1600 4200);
PAINT GREEN (-1600 4200);
DISPLAY INVISIBLE (-1600 4200);
FORCEPROP 1 LAST HDL_TAP TRUE
J 2
(-1925 4125);
DISPLAY 1.234043 (-1925 4125);
PAINT GREEN (-1925 4125);
DISPLAY INVISIBLE (-1925 4125);
FORCEPROP 1 LAST PATH I59
J 2
(-1600 4250);
DISPLAY 0.936170 (-1600 4250);
PAINT GREEN (-1600 4250);
DISPLAY INVISIBLE (-1600 4250);
FORCEADD TAP..6
R 2
(900 4900);
FORCEPROP 3 LASTPIN (850 4900) SIG_NAME M_E_DQS_DN<15>
J 0
(860 4910);
DISPLAY 0.659574 (860 4910);
PAINT MONO (860 4910);
DISPLAY INVISIBLE (860 4910);
FORCEPROP 1 LASTPIN (850 4900) BN 15
J 2
(900 4910);
DISPLAY 0.617021 (900 4910);
PAINT PINK (900 4910);
FORCEPROP 2 LAST CDS_LIB mstr_standard
J 0
(900 4900);
DISPLAY 0.787234 (900 4900);
PAINT MONO (900 4900);
DISPLAY INVISIBLE (900 4900);
FORCEPROP 1 LAST BODY_TYPE PLUMBING
J 2
(900 4850);
DISPLAY 1.234043 (900 4850);
PAINT GREEN (900 4850);
DISPLAY INVISIBLE (900 4850);
FORCEPROP 1 LAST HDL_TAP TRUE
J 2
(575 4775);
DISPLAY 1.234043 (575 4775);
PAINT GREEN (575 4775);
DISPLAY INVISIBLE (575 4775);
FORCEPROP 1 LAST PATH I6
J 2
(900 4900);
DISPLAY 0.936170 (900 4900);
PAINT GREEN (900 4900);
DISPLAY INVISIBLE (900 4900);
FORCEADD TAP..6
R 2
(-1600 4200);
FORCEPROP 3 LASTPIN (-1650 4200) SIG_NAME M_E_DQ<48>
J 0
(-1640 4210);
DISPLAY 0.659574 (-1640 4210);
PAINT MONO (-1640 4210);
DISPLAY INVISIBLE (-1640 4210);
FORCEPROP 1 LASTPIN (-1650 4200) BN 48
J 2
(-1600 4210);
DISPLAY 0.617021 (-1600 4210);
PAINT PINK (-1600 4210);
FORCEPROP 2 LAST CDS_LIB mstr_standard
J 2
(-1600 4200);
DISPLAY 0.787234 (-1600 4200);
PAINT MONO (-1600 4200);
DISPLAY INVISIBLE (-1600 4200);
FORCEPROP 1 LAST BODY_TYPE PLUMBING
J 2
(-1600 4150);
DISPLAY 1.234043 (-1600 4150);
PAINT GREEN (-1600 4150);
DISPLAY INVISIBLE (-1600 4150);
FORCEPROP 1 LAST HDL_TAP TRUE
J 2
(-1925 4075);
DISPLAY 1.234043 (-1925 4075);
PAINT GREEN (-1925 4075);
DISPLAY INVISIBLE (-1925 4075);
FORCEPROP 1 LAST PATH I60
J 2
(-1600 4200);
DISPLAY 0.936170 (-1600 4200);
PAINT GREEN (-1600 4200);
DISPLAY INVISIBLE (-1600 4200);
FORCEADD TAP..6
R 2
(-1600 4100);
FORCEPROP 3 LASTPIN (-1650 4100) SIG_NAME M_E_DQ<46>
J 0
(-1640 4110);
DISPLAY 0.659574 (-1640 4110);
PAINT MONO (-1640 4110);
DISPLAY INVISIBLE (-1640 4110);
FORCEPROP 1 LASTPIN (-1650 4100) BN 46
J 2
(-1600 4110);
DISPLAY 0.617021 (-1600 4110);
PAINT PINK (-1600 4110);
FORCEPROP 2 LAST CDS_LIB mstr_standard
J 2
(-1600 4100);
DISPLAY 0.787234 (-1600 4100);
PAINT MONO (-1600 4100);
DISPLAY INVISIBLE (-1600 4100);
FORCEPROP 1 LAST BODY_TYPE PLUMBING
J 2
(-1600 4050);
DISPLAY 1.234043 (-1600 4050);
PAINT GREEN (-1600 4050);
DISPLAY INVISIBLE (-1600 4050);
FORCEPROP 1 LAST HDL_TAP TRUE
J 2
(-1925 3975);
DISPLAY 1.234043 (-1925 3975);
PAINT GREEN (-1925 3975);
DISPLAY INVISIBLE (-1925 3975);
FORCEPROP 1 LAST PATH I61
J 2
(-1600 4100);
DISPLAY 0.936170 (-1600 4100);
PAINT GREEN (-1600 4100);
DISPLAY INVISIBLE (-1600 4100);
FORCEADD TAP..6
R 2
(-1600 4150);
FORCEPROP 3 LASTPIN (-1650 4150) SIG_NAME M_E_DQ<49>
J 0
(-1640 4160);
DISPLAY 0.659574 (-1640 4160);
PAINT MONO (-1640 4160);
DISPLAY INVISIBLE (-1640 4160);
FORCEPROP 1 LASTPIN (-1650 4150) BN 49
J 2
(-1600 4160);
DISPLAY 0.617021 (-1600 4160);
PAINT PINK (-1600 4160);
FORCEPROP 2 LAST CDS_LIB mstr_standard
J 2
(-1600 4150);
DISPLAY 0.787234 (-1600 4150);
PAINT MONO (-1600 4150);
DISPLAY INVISIBLE (-1600 4150);
FORCEPROP 1 LAST BODY_TYPE PLUMBING
J 2
(-1600 4100);
DISPLAY 1.234043 (-1600 4100);
PAINT GREEN (-1600 4100);
DISPLAY INVISIBLE (-1600 4100);
FORCEPROP 1 LAST HDL_TAP TRUE
J 2
(-1925 4025);
DISPLAY 1.234043 (-1925 4025);
PAINT GREEN (-1925 4025);
DISPLAY INVISIBLE (-1925 4025);
FORCEPROP 1 LAST PATH I62
J 2
(-1600 4150);
DISPLAY 0.936170 (-1600 4150);
PAINT GREEN (-1600 4150);
DISPLAY INVISIBLE (-1600 4150);
FORCEADD TAP..6
R 2
(-1600 4050);
FORCEPROP 3 LASTPIN (-1650 4050) SIG_NAME M_E_DQ<47>
J 0
(-1640 4060);
DISPLAY 0.659574 (-1640 4060);
PAINT MONO (-1640 4060);
DISPLAY INVISIBLE (-1640 4060);
FORCEPROP 1 LASTPIN (-1650 4050) BN 47
J 2
(-1600 4060);
DISPLAY 0.617021 (-1600 4060);
PAINT PINK (-1600 4060);
FORCEPROP 2 LAST CDS_LIB mstr_standard
J 2
(-1600 4050);
DISPLAY 0.787234 (-1600 4050);
PAINT MONO (-1600 4050);
DISPLAY INVISIBLE (-1600 4050);
FORCEPROP 1 LAST BODY_TYPE PLUMBING
J 2
(-1600 4000);
DISPLAY 1.234043 (-1600 4000);
PAINT GREEN (-1600 4000);
DISPLAY INVISIBLE (-1600 4000);
FORCEPROP 1 LAST HDL_TAP TRUE
J 2
(-1925 3925);
DISPLAY 1.234043 (-1925 3925);
PAINT GREEN (-1925 3925);
DISPLAY INVISIBLE (-1925 3925);
FORCEPROP 1 LAST PATH I63
J 2
(-1600 4050);
DISPLAY 0.936170 (-1600 4050);
PAINT GREEN (-1600 4050);
DISPLAY INVISIBLE (-1600 4050);
FORCEADD TAP..6
R 2
(-1600 4000);
FORCEPROP 3 LASTPIN (-1650 4000) SIG_NAME M_E_DQ<44>
J 0
(-1640 4010);
DISPLAY 0.659574 (-1640 4010);
PAINT MONO (-1640 4010);
DISPLAY INVISIBLE (-1640 4010);
FORCEPROP 1 LASTPIN (-1650 4000) BN 44
J 2
(-1600 4010);
DISPLAY 0.617021 (-1600 4010);
PAINT PINK (-1600 4010);
FORCEPROP 2 LAST CDS_LIB mstr_standard
J 2
(-1600 4000);
DISPLAY 0.787234 (-1600 4000);
PAINT MONO (-1600 4000);
DISPLAY INVISIBLE (-1600 4000);
FORCEPROP 1 LAST BODY_TYPE PLUMBING
J 2
(-1600 3950);
DISPLAY 1.234043 (-1600 3950);
PAINT GREEN (-1600 3950);
DISPLAY INVISIBLE (-1600 3950);
FORCEPROP 1 LAST HDL_TAP TRUE
J 2
(-1925 3875);
DISPLAY 1.234043 (-1925 3875);
PAINT GREEN (-1925 3875);
DISPLAY INVISIBLE (-1925 3875);
FORCEPROP 1 LAST PATH I64
J 2
(-1600 4000);
DISPLAY 0.936170 (-1600 4000);
PAINT GREEN (-1600 4000);
DISPLAY INVISIBLE (-1600 4000);
FORCEADD TAP..6
R 2
(-1600 3950);
FORCEPROP 3 LASTPIN (-1650 3950) SIG_NAME M_E_DQ<45>
J 0
(-1640 3960);
DISPLAY 0.659574 (-1640 3960);
PAINT MONO (-1640 3960);
DISPLAY INVISIBLE (-1640 3960);
FORCEPROP 1 LASTPIN (-1650 3950) BN 45
J 2
(-1600 3960);
DISPLAY 0.617021 (-1600 3960);
PAINT PINK (-1600 3960);
FORCEPROP 2 LAST CDS_LIB mstr_standard
J 2
(-1600 3950);
DISPLAY 0.787234 (-1600 3950);
PAINT MONO (-1600 3950);
DISPLAY INVISIBLE (-1600 3950);
FORCEPROP 1 LAST BODY_TYPE PLUMBING
J 2
(-1600 3900);
DISPLAY 1.234043 (-1600 3900);
PAINT GREEN (-1600 3900);
DISPLAY INVISIBLE (-1600 3900);
FORCEPROP 1 LAST HDL_TAP TRUE
J 2
(-1925 3825);
DISPLAY 1.234043 (-1925 3825);
PAINT GREEN (-1925 3825);
DISPLAY INVISIBLE (-1925 3825);
FORCEPROP 1 LAST PATH I65
J 2
(-1600 3950);
DISPLAY 0.936170 (-1600 3950);
PAINT GREEN (-1600 3950);
DISPLAY INVISIBLE (-1600 3950);
FORCEADD SCONN288_H44441004..2
(0 4300);
FORCEPROP 1 LAST LOCATION J4A2
J 0
(-400 5400);
DISPLAY 0.617021 (-400 5400);
PAINT AQUA (-400 5400);
FORCEPROP 1 LAST PART_NUMBER H44441-004
J 0
(-400 3200);
DISPLAY 0.617021 (-400 3200);
PAINT BLUE (-400 3200);
FORCEPROP 1 LAST MATERIAL SCONN
J 0
(-400 5350);
DISPLAY 0.617021 (-400 5350);
PAINT SKYBLUE (-400 5350);
FORCEPROP 2 LASTPIN (450 5150) $PN 51
J 0
(460 5160);
DISPLAY 0.617021 (460 5160);
PAINT ORANGE (460 5160);
FORCEPROP 2 LASTPIN (450 5100) $PN 52
J 0
(460 5110);
DISPLAY 0.617021 (460 5110);
PAINT ORANGE (460 5110);
FORCEPROP 2 LASTPIN (450 5050) $PN 132
J 0
(460 5060);
DISPLAY 0.617021 (460 5060);
PAINT ORANGE (460 5060);
FORCEPROP 2 LASTPIN (450 5000) $PN 133
J 0
(460 5010);
DISPLAY 0.617021 (460 5010);
PAINT ORANGE (460 5010);
FORCEPROP 2 LASTPIN (450 4950) $PN 121
J 0
(460 4960);
DISPLAY 0.617021 (460 4960);
PAINT ORANGE (460 4960);
FORCEPROP 2 LASTPIN (450 4900) $PN 122
J 0
(460 4910);
DISPLAY 0.617021 (460 4910);
PAINT ORANGE (460 4910);
FORCEPROP 2 LASTPIN (450 4850) $PN 110
J 0
(460 4860);
DISPLAY 0.617021 (460 4860);
PAINT ORANGE (460 4860);
FORCEPROP 2 LASTPIN (450 4800) $PN 111
J 0
(460 4810);
DISPLAY 0.617021 (460 4810);
PAINT ORANGE (460 4810);
FORCEPROP 2 LASTPIN (450 4750) $PN 99
J 0
(460 4760);
DISPLAY 0.617021 (460 4760);
PAINT ORANGE (460 4760);
FORCEPROP 2 LASTPIN (450 4700) $PN 100
J 0
(460 4710);
DISPLAY 0.617021 (460 4710);
PAINT ORANGE (460 4710);
FORCEPROP 2 LASTPIN (450 4650) $PN 40
J 0
(460 4660);
DISPLAY 0.617021 (460 4660);
PAINT ORANGE (460 4660);
FORCEPROP 2 LASTPIN (450 4600) $PN 41
J 0
(460 4610);
DISPLAY 0.617021 (460 4610);
PAINT ORANGE (460 4610);
FORCEPROP 2 LASTPIN (450 4550) $PN 29
J 0
(460 4560);
DISPLAY 0.617021 (460 4560);
PAINT ORANGE (460 4560);
FORCEPROP 2 LASTPIN (450 4500) $PN 30
J 0
(460 4510);
DISPLAY 0.617021 (460 4510);
PAINT ORANGE (460 4510);
FORCEPROP 2 LASTPIN (450 4450) $PN 18
J 0
(460 4460);
DISPLAY 0.617021 (460 4460);
PAINT ORANGE (460 4460);
FORCEPROP 2 LASTPIN (450 4400) $PN 19
J 0
(460 4410);
DISPLAY 0.617021 (460 4410);
PAINT ORANGE (460 4410);
FORCEPROP 2 LASTPIN (450 4350) $PN 7
J 0
(460 4360);
DISPLAY 0.617021 (460 4360);
PAINT ORANGE (460 4360);
FORCEPROP 2 LASTPIN (450 4300) $PN 8
J 0
(460 4310);
DISPLAY 0.617021 (460 4310);
PAINT ORANGE (460 4310);
FORCEPROP 2 LASTPIN (450 4250) $PN 197
J 0
(460 4260);
DISPLAY 0.617021 (460 4260);
PAINT ORANGE (460 4260);
FORCEPROP 2 LASTPIN (450 4200) $PN 196
J 0
(460 4210);
DISPLAY 0.617021 (460 4210);
PAINT ORANGE (460 4210);
FORCEPROP 2 LASTPIN (450 4150) $PN 278
J 0
(460 4160);
DISPLAY 0.617021 (460 4160);
PAINT ORANGE (460 4160);
FORCEPROP 2 LASTPIN (450 4100) $PN 277
J 0
(460 4110);
DISPLAY 0.617021 (460 4110);
PAINT ORANGE (460 4110);
FORCEPROP 2 LASTPIN (450 4050) $PN 267
J 0
(460 4060);
DISPLAY 0.617021 (460 4060);
PAINT ORANGE (460 4060);
FORCEPROP 2 LASTPIN (450 4000) $PN 266
J 0
(460 4010);
DISPLAY 0.617021 (460 4010);
PAINT ORANGE (460 4010);
FORCEPROP 2 LASTPIN (450 3950) $PN 256
J 0
(460 3960);
DISPLAY 0.617021 (460 3960);
PAINT ORANGE (460 3960);
FORCEPROP 2 LASTPIN (450 3900) $PN 255
J 0
(460 3910);
DISPLAY 0.617021 (460 3910);
PAINT ORANGE (460 3910);
FORCEPROP 2 LASTPIN (450 3850) $PN 245
J 0
(460 3860);
DISPLAY 0.617021 (460 3860);
PAINT ORANGE (460 3860);
FORCEPROP 2 LASTPIN (450 3800) $PN 244
J 0
(460 3810);
DISPLAY 0.617021 (460 3810);
PAINT ORANGE (460 3810);
FORCEPROP 2 LASTPIN (450 3750) $PN 186
J 0
(460 3760);
DISPLAY 0.617021 (460 3760);
PAINT ORANGE (460 3760);
FORCEPROP 2 LASTPIN (450 3700) $PN 185
J 0
(460 3710);
DISPLAY 0.617021 (460 3710);
PAINT ORANGE (460 3710);
FORCEPROP 2 LASTPIN (450 3650) $PN 175
J 0
(460 3660);
DISPLAY 0.617021 (460 3660);
PAINT ORANGE (460 3660);
FORCEPROP 2 LASTPIN (450 3600) $PN 174
J 0
(460 3610);
DISPLAY 0.617021 (460 3610);
PAINT ORANGE (460 3610);
FORCEPROP 2 LASTPIN (450 3550) $PN 164
J 0
(460 3560);
DISPLAY 0.617021 (460 3560);
PAINT ORANGE (460 3560);
FORCEPROP 2 LASTPIN (450 3500) $PN 163
J 0
(460 3510);
DISPLAY 0.617021 (460 3510);
PAINT ORANGE (460 3510);
FORCEPROP 2 LASTPIN (450 3450) $PN 153
J 0
(460 3460);
DISPLAY 0.617021 (460 3460);
PAINT ORANGE (460 3460);
FORCEPROP 2 LASTPIN (450 3400) $PN 152
J 0
(460 3410);
DISPLAY 0.617021 (460 3410);
PAINT ORANGE (460 3410);
FORCEPROP 1 LAST PACK_TYPE PIP
J 0
(-400 5450);
PAINT SKYBLUE (-400 5450);
DISPLAY INVISIBLE (-400 5450);
FORCEPROP 2 LAST BOM_COST MEM
J 0
(0 4300);
PAINT ORANGE (0 4300);
DISPLAY INVISIBLE (0 4300);
FORCEPROP 2 LAST CDS_LIB mstr_sconn
J 0
(0 4300);
PAINT ORANGE (0 4300);
DISPLAY INVISIBLE (0 4300);
FORCEPROP 2 LAST SEC_TYPE PIP
J 0
(-400 5450);
DISPLAY 1.021277 (-400 5450);
PAINT ORANGE (-400 5450);
DISPLAY INVISIBLE (-400 5450);
FORCEPROP 2 LAST SEC 2
J 0
(-400 5450);
DISPLAY 0.680851 (-400 5450);
PAINT MONO (-400 5450);
DISPLAY INVISIBLE (-400 5450);
FORCEPROP 2 LAST CDS_LOCATION J4A2
J 0
(-400 5400);
DISPLAY 0.617021 (-400 5400);
PAINT AQUA (-400 5400);
DISPLAY INVISIBLE (-400 5400);
FORCEPROP 1 LAST PATH I66
J 0
(0 5350);
PAINT GREEN (0 5350);
DISPLAY INVISIBLE (0 5350);
FORCEPROP 2 LAST ROOM DDR4_CH_E
J 0
(-400 5500);
PAINT ORANGE (-400 5500);
DISPLAY INVISIBLE (-400 5500);
FORCEADD TAP..6
R 2
(-1600 3900);
FORCEPROP 3 LASTPIN (-1650 3900) SIG_NAME M_E_DQ<42>
J 0
(-1640 3910);
DISPLAY 0.659574 (-1640 3910);
PAINT MONO (-1640 3910);
DISPLAY INVISIBLE (-1640 3910);
FORCEPROP 1 LASTPIN (-1650 3900) BN 42
J 2
(-1600 3910);
DISPLAY 0.617021 (-1600 3910);
PAINT PINK (-1600 3910);
FORCEPROP 2 LAST CDS_LIB mstr_standard
J 2
(-1600 3900);
DISPLAY 0.787234 (-1600 3900);
PAINT MONO (-1600 3900);
DISPLAY INVISIBLE (-1600 3900);
FORCEPROP 1 LAST BODY_TYPE PLUMBING
J 2
(-1600 3850);
DISPLAY 1.234043 (-1600 3850);
PAINT GREEN (-1600 3850);
DISPLAY INVISIBLE (-1600 3850);
FORCEPROP 1 LAST HDL_TAP TRUE
J 2
(-1925 3775);
DISPLAY 1.234043 (-1925 3775);
PAINT GREEN (-1925 3775);
DISPLAY INVISIBLE (-1925 3775);
FORCEPROP 1 LAST PATH I67
J 2
(-1600 3900);
DISPLAY 0.936170 (-1600 3900);
PAINT GREEN (-1600 3900);
DISPLAY INVISIBLE (-1600 3900);
FORCEADD TAP..6
R 2
(-1600 3850);
FORCEPROP 3 LASTPIN (-1650 3850) SIG_NAME M_E_DQ<43>
J 0
(-1640 3860);
DISPLAY 0.659574 (-1640 3860);
PAINT MONO (-1640 3860);
DISPLAY INVISIBLE (-1640 3860);
FORCEPROP 1 LASTPIN (-1650 3850) BN 43
J 2
(-1600 3860);
DISPLAY 0.617021 (-1600 3860);
PAINT PINK (-1600 3860);
FORCEPROP 2 LAST CDS_LIB mstr_standard
J 2
(-1600 3850);
DISPLAY 0.787234 (-1600 3850);
PAINT MONO (-1600 3850);
DISPLAY INVISIBLE (-1600 3850);
FORCEPROP 1 LAST BODY_TYPE PLUMBING
J 2
(-1600 3800);
DISPLAY 1.234043 (-1600 3800);
PAINT GREEN (-1600 3800);
DISPLAY INVISIBLE (-1600 3800);
FORCEPROP 1 LAST HDL_TAP TRUE
J 2
(-1925 3725);
DISPLAY 1.234043 (-1925 3725);
PAINT GREEN (-1925 3725);
DISPLAY INVISIBLE (-1925 3725);
FORCEPROP 1 LAST PATH I68
J 2
(-1600 3850);
DISPLAY 0.936170 (-1600 3850);
PAINT GREEN (-1600 3850);
DISPLAY INVISIBLE (-1600 3850);
FORCEADD TAP..6
R 2
(-1600 3750);
FORCEPROP 3 LASTPIN (-1650 3750) SIG_NAME M_E_DQ<41>
J 0
(-1640 3760);
DISPLAY 0.659574 (-1640 3760);
PAINT MONO (-1640 3760);
DISPLAY INVISIBLE (-1640 3760);
FORCEPROP 1 LASTPIN (-1650 3750) BN 41
J 2
(-1600 3760);
DISPLAY 0.617021 (-1600 3760);
PAINT PINK (-1600 3760);
FORCEPROP 2 LAST CDS_LIB mstr_standard
J 2
(-1600 3750);
DISPLAY 0.787234 (-1600 3750);
PAINT MONO (-1600 3750);
DISPLAY INVISIBLE (-1600 3750);
FORCEPROP 1 LAST BODY_TYPE PLUMBING
J 2
(-1600 3700);
DISPLAY 1.234043 (-1600 3700);
PAINT GREEN (-1600 3700);
DISPLAY INVISIBLE (-1600 3700);
FORCEPROP 1 LAST HDL_TAP TRUE
J 2
(-1925 3625);
DISPLAY 1.234043 (-1925 3625);
PAINT GREEN (-1925 3625);
DISPLAY INVISIBLE (-1925 3625);
FORCEPROP 1 LAST PATH I69
J 2
(-1600 3750);
DISPLAY 0.936170 (-1600 3750);
PAINT GREEN (-1600 3750);
DISPLAY INVISIBLE (-1600 3750);
FORCEADD TAP..6
R 2
(900 4700);
FORCEPROP 3 LASTPIN (850 4700) SIG_NAME M_E_DQS_DN<13>
J 0
(860 4710);
DISPLAY 0.659574 (860 4710);
PAINT MONO (860 4710);
DISPLAY INVISIBLE (860 4710);
FORCEPROP 1 LASTPIN (850 4700) BN 13
J 2
(900 4710);
DISPLAY 0.617021 (900 4710);
PAINT PINK (900 4710);
FORCEPROP 2 LAST CDS_LIB mstr_standard
J 0
(900 4700);
DISPLAY 0.787234 (900 4700);
PAINT MONO (900 4700);
DISPLAY INVISIBLE (900 4700);
FORCEPROP 1 LAST BODY_TYPE PLUMBING
J 2
(900 4650);
DISPLAY 1.234043 (900 4650);
PAINT GREEN (900 4650);
DISPLAY INVISIBLE (900 4650);
FORCEPROP 1 LAST HDL_TAP TRUE
J 2
(575 4575);
DISPLAY 1.234043 (575 4575);
PAINT GREEN (575 4575);
DISPLAY INVISIBLE (575 4575);
FORCEPROP 1 LAST PATH I7
J 2
(900 4700);
DISPLAY 0.936170 (900 4700);
PAINT GREEN (900 4700);
DISPLAY INVISIBLE (900 4700);
FORCEADD TAP..6
R 2
(-1600 3700);
FORCEPROP 3 LASTPIN (-1650 3700) SIG_NAME M_E_DQ<38>
J 0
(-1640 3710);
DISPLAY 0.659574 (-1640 3710);
PAINT MONO (-1640 3710);
DISPLAY INVISIBLE (-1640 3710);
FORCEPROP 1 LASTPIN (-1650 3700) BN 38
J 2
(-1600 3710);
DISPLAY 0.617021 (-1600 3710);
PAINT PINK (-1600 3710);
FORCEPROP 2 LAST CDS_LIB mstr_standard
J 2
(-1600 3700);
DISPLAY 0.787234 (-1600 3700);
PAINT MONO (-1600 3700);
DISPLAY INVISIBLE (-1600 3700);
FORCEPROP 1 LAST BODY_TYPE PLUMBING
J 2
(-1600 3650);
DISPLAY 1.234043 (-1600 3650);
PAINT GREEN (-1600 3650);
DISPLAY INVISIBLE (-1600 3650);
FORCEPROP 1 LAST HDL_TAP TRUE
J 2
(-1925 3575);
DISPLAY 1.234043 (-1925 3575);
PAINT GREEN (-1925 3575);
DISPLAY INVISIBLE (-1925 3575);
FORCEPROP 1 LAST PATH I70
J 2
(-1600 3700);
DISPLAY 0.936170 (-1600 3700);
PAINT GREEN (-1600 3700);
DISPLAY INVISIBLE (-1600 3700);
FORCEADD TAP..6
R 2
(-1600 3800);
FORCEPROP 3 LASTPIN (-1650 3800) SIG_NAME M_E_DQ<40>
J 0
(-1640 3810);
DISPLAY 0.659574 (-1640 3810);
PAINT MONO (-1640 3810);
DISPLAY INVISIBLE (-1640 3810);
FORCEPROP 1 LASTPIN (-1650 3800) BN 40
J 2
(-1600 3810);
DISPLAY 0.617021 (-1600 3810);
PAINT PINK (-1600 3810);
FORCEPROP 2 LAST CDS_LIB mstr_standard
J 2
(-1600 3800);
DISPLAY 0.787234 (-1600 3800);
PAINT MONO (-1600 3800);
DISPLAY INVISIBLE (-1600 3800);
FORCEPROP 1 LAST BODY_TYPE PLUMBING
J 2
(-1600 3750);
DISPLAY 1.234043 (-1600 3750);
PAINT GREEN (-1600 3750);
DISPLAY INVISIBLE (-1600 3750);
FORCEPROP 1 LAST HDL_TAP TRUE
J 2
(-1925 3675);
DISPLAY 1.234043 (-1925 3675);
PAINT GREEN (-1925 3675);
DISPLAY INVISIBLE (-1925 3675);
FORCEPROP 1 LAST PATH I71
J 2
(-1600 3800);
DISPLAY 0.936170 (-1600 3800);
PAINT GREEN (-1600 3800);
DISPLAY INVISIBLE (-1600 3800);
FORCEADD TAP..6
R 2
(-1600 3650);
FORCEPROP 3 LASTPIN (-1650 3650) SIG_NAME M_E_DQ<39>
J 0
(-1640 3660);
DISPLAY 0.659574 (-1640 3660);
PAINT MONO (-1640 3660);
DISPLAY INVISIBLE (-1640 3660);
FORCEPROP 1 LASTPIN (-1650 3650) BN 39
J 2
(-1600 3660);
DISPLAY 0.617021 (-1600 3660);
PAINT PINK (-1600 3660);
FORCEPROP 2 LAST CDS_LIB mstr_standard
J 2
(-1600 3650);
DISPLAY 0.787234 (-1600 3650);
PAINT MONO (-1600 3650);
DISPLAY INVISIBLE (-1600 3650);
FORCEPROP 1 LAST BODY_TYPE PLUMBING
J 2
(-1600 3600);
DISPLAY 1.234043 (-1600 3600);
PAINT GREEN (-1600 3600);
DISPLAY INVISIBLE (-1600 3600);
FORCEPROP 1 LAST HDL_TAP TRUE
J 2
(-1925 3525);
DISPLAY 1.234043 (-1925 3525);
PAINT GREEN (-1925 3525);
DISPLAY INVISIBLE (-1925 3525);
FORCEPROP 1 LAST PATH I72
J 2
(-1600 3650);
DISPLAY 0.936170 (-1600 3650);
PAINT GREEN (-1600 3650);
DISPLAY INVISIBLE (-1600 3650);
FORCEADD TAP..6
R 2
(-1600 3600);
FORCEPROP 3 LASTPIN (-1650 3600) SIG_NAME M_E_DQ<36>
J 0
(-1640 3610);
DISPLAY 0.659574 (-1640 3610);
PAINT MONO (-1640 3610);
DISPLAY INVISIBLE (-1640 3610);
FORCEPROP 1 LASTPIN (-1650 3600) BN 36
J 2
(-1600 3610);
DISPLAY 0.617021 (-1600 3610);
PAINT PINK (-1600 3610);
FORCEPROP 2 LAST CDS_LIB mstr_standard
J 2
(-1600 3600);
DISPLAY 0.787234 (-1600 3600);
PAINT MONO (-1600 3600);
DISPLAY INVISIBLE (-1600 3600);
FORCEPROP 1 LAST BODY_TYPE PLUMBING
J 2
(-1600 3550);
DISPLAY 1.234043 (-1600 3550);
PAINT GREEN (-1600 3550);
DISPLAY INVISIBLE (-1600 3550);
FORCEPROP 1 LAST HDL_TAP TRUE
J 2
(-1925 3475);
DISPLAY 1.234043 (-1925 3475);
PAINT GREEN (-1925 3475);
DISPLAY INVISIBLE (-1925 3475);
FORCEPROP 1 LAST PATH I73
J 2
(-1600 3600);
DISPLAY 0.936170 (-1600 3600);
PAINT GREEN (-1600 3600);
DISPLAY INVISIBLE (-1600 3600);
FORCEADD TAP..6
R 2
(-1600 3550);
FORCEPROP 3 LASTPIN (-1650 3550) SIG_NAME M_E_DQ<37>
J 0
(-1640 3560);
DISPLAY 0.659574 (-1640 3560);
PAINT MONO (-1640 3560);
DISPLAY INVISIBLE (-1640 3560);
FORCEPROP 1 LASTPIN (-1650 3550) BN 37
J 2
(-1600 3560);
DISPLAY 0.617021 (-1600 3560);
PAINT PINK (-1600 3560);
FORCEPROP 2 LAST CDS_LIB mstr_standard
J 2
(-1600 3550);
DISPLAY 0.787234 (-1600 3550);
PAINT MONO (-1600 3550);
DISPLAY INVISIBLE (-1600 3550);
FORCEPROP 1 LAST BODY_TYPE PLUMBING
J 2
(-1600 3500);
DISPLAY 1.234043 (-1600 3500);
PAINT GREEN (-1600 3500);
DISPLAY INVISIBLE (-1600 3500);
FORCEPROP 1 LAST HDL_TAP TRUE
J 2
(-1925 3425);
DISPLAY 1.234043 (-1925 3425);
PAINT GREEN (-1925 3425);
DISPLAY INVISIBLE (-1925 3425);
FORCEPROP 1 LAST PATH I74
J 2
(-1600 3550);
DISPLAY 0.936170 (-1600 3550);
PAINT GREEN (-1600 3550);
DISPLAY INVISIBLE (-1600 3550);
FORCEADD TAP..6
R 2
(-1600 3450);
FORCEPROP 3 LASTPIN (-1650 3450) SIG_NAME M_E_DQ<35>
J 0
(-1640 3460);
DISPLAY 0.659574 (-1640 3460);
PAINT MONO (-1640 3460);
DISPLAY INVISIBLE (-1640 3460);
FORCEPROP 1 LASTPIN (-1650 3450) BN 35
J 2
(-1600 3460);
DISPLAY 0.617021 (-1600 3460);
PAINT PINK (-1600 3460);
FORCEPROP 2 LAST CDS_LIB mstr_standard
J 2
(-1600 3450);
DISPLAY 0.787234 (-1600 3450);
PAINT MONO (-1600 3450);
DISPLAY INVISIBLE (-1600 3450);
FORCEPROP 1 LAST BODY_TYPE PLUMBING
J 2
(-1600 3400);
DISPLAY 1.234043 (-1600 3400);
PAINT GREEN (-1600 3400);
DISPLAY INVISIBLE (-1600 3400);
FORCEPROP 1 LAST HDL_TAP TRUE
J 2
(-1925 3325);
DISPLAY 1.234043 (-1925 3325);
PAINT GREEN (-1925 3325);
DISPLAY INVISIBLE (-1925 3325);
FORCEPROP 1 LAST PATH I75
J 2
(-1600 3450);
DISPLAY 0.936170 (-1600 3450);
PAINT GREEN (-1600 3450);
DISPLAY INVISIBLE (-1600 3450);
FORCEADD TAP..6
R 2
(-1600 3500);
FORCEPROP 3 LASTPIN (-1650 3500) SIG_NAME M_E_DQ<34>
J 0
(-1640 3510);
DISPLAY 0.659574 (-1640 3510);
PAINT MONO (-1640 3510);
DISPLAY INVISIBLE (-1640 3510);
FORCEPROP 1 LASTPIN (-1650 3500) BN 34
J 2
(-1600 3510);
DISPLAY 0.617021 (-1600 3510);
PAINT PINK (-1600 3510);
FORCEPROP 2 LAST CDS_LIB mstr_standard
J 2
(-1600 3500);
DISPLAY 0.787234 (-1600 3500);
PAINT MONO (-1600 3500);
DISPLAY INVISIBLE (-1600 3500);
FORCEPROP 1 LAST BODY_TYPE PLUMBING
J 2
(-1600 3450);
DISPLAY 1.234043 (-1600 3450);
PAINT GREEN (-1600 3450);
DISPLAY INVISIBLE (-1600 3450);
FORCEPROP 1 LAST HDL_TAP TRUE
J 2
(-1925 3375);
DISPLAY 1.234043 (-1925 3375);
PAINT GREEN (-1925 3375);
DISPLAY INVISIBLE (-1925 3375);
FORCEPROP 1 LAST PATH I76
J 2
(-1600 3500);
DISPLAY 0.936170 (-1600 3500);
PAINT GREEN (-1600 3500);
DISPLAY INVISIBLE (-1600 3500);
FORCEADD TAP..6
R 2
(-1600 3400);
FORCEPROP 3 LASTPIN (-1650 3400) SIG_NAME M_E_DQ<32>
J 0
(-1640 3410);
DISPLAY 0.659574 (-1640 3410);
PAINT MONO (-1640 3410);
DISPLAY INVISIBLE (-1640 3410);
FORCEPROP 1 LASTPIN (-1650 3400) BN 32
J 2
(-1600 3410);
DISPLAY 0.617021 (-1600 3410);
PAINT PINK (-1600 3410);
FORCEPROP 2 LAST CDS_LIB mstr_standard
J 2
(-1600 3400);
DISPLAY 0.787234 (-1600 3400);
PAINT MONO (-1600 3400);
DISPLAY INVISIBLE (-1600 3400);
FORCEPROP 1 LAST BODY_TYPE PLUMBING
J 2
(-1600 3350);
DISPLAY 1.234043 (-1600 3350);
PAINT GREEN (-1600 3350);
DISPLAY INVISIBLE (-1600 3350);
FORCEPROP 1 LAST HDL_TAP TRUE
J 2
(-1925 3275);
DISPLAY 1.234043 (-1925 3275);
PAINT GREEN (-1925 3275);
DISPLAY INVISIBLE (-1925 3275);
FORCEPROP 1 LAST PATH I77
J 2
(-1600 3400);
DISPLAY 0.936170 (-1600 3400);
PAINT GREEN (-1600 3400);
DISPLAY INVISIBLE (-1600 3400);
FORCEADD TAP..6
R 2
(-1600 3350);
FORCEPROP 3 LASTPIN (-1650 3350) SIG_NAME M_E_DQ<33>
J 0
(-1640 3360);
DISPLAY 0.659574 (-1640 3360);
PAINT MONO (-1640 3360);
DISPLAY INVISIBLE (-1640 3360);
FORCEPROP 1 LASTPIN (-1650 3350) BN 33
J 2
(-1600 3360);
DISPLAY 0.617021 (-1600 3360);
PAINT PINK (-1600 3360);
FORCEPROP 2 LAST CDS_LIB mstr_standard
J 2
(-1600 3350);
DISPLAY 0.787234 (-1600 3350);
PAINT MONO (-1600 3350);
DISPLAY INVISIBLE (-1600 3350);
FORCEPROP 1 LAST BODY_TYPE PLUMBING
J 2
(-1600 3300);
DISPLAY 1.234043 (-1600 3300);
PAINT GREEN (-1600 3300);
DISPLAY INVISIBLE (-1600 3300);
FORCEPROP 1 LAST HDL_TAP TRUE
J 2
(-1925 3225);
DISPLAY 1.234043 (-1925 3225);
PAINT GREEN (-1925 3225);
DISPLAY INVISIBLE (-1925 3225);
FORCEPROP 1 LAST PATH I78
J 2
(-1600 3350);
DISPLAY 0.936170 (-1600 3350);
PAINT GREEN (-1600 3350);
DISPLAY INVISIBLE (-1600 3350);
FORCEADD TAP..6
R 2
(-1600 3200);
FORCEPROP 3 LASTPIN (-1650 3200) SIG_NAME M_E_DQ<28>
J 0
(-1640 3210);
DISPLAY 0.659574 (-1640 3210);
PAINT MONO (-1640 3210);
DISPLAY INVISIBLE (-1640 3210);
FORCEPROP 1 LASTPIN (-1650 3200) BN 28
J 2
(-1600 3210);
DISPLAY 0.617021 (-1600 3210);
PAINT PINK (-1600 3210);
FORCEPROP 2 LAST CDS_LIB mstr_standard
J 2
(-1600 3200);
DISPLAY 0.787234 (-1600 3200);
PAINT MONO (-1600 3200);
DISPLAY INVISIBLE (-1600 3200);
FORCEPROP 1 LAST BODY_TYPE PLUMBING
J 2
(-1600 3150);
DISPLAY 1.234043 (-1600 3150);
PAINT GREEN (-1600 3150);
DISPLAY INVISIBLE (-1600 3150);
FORCEPROP 1 LAST HDL_TAP TRUE
J 2
(-1925 3075);
DISPLAY 1.234043 (-1925 3075);
PAINT GREEN (-1925 3075);
DISPLAY INVISIBLE (-1925 3075);
FORCEPROP 1 LAST PATH I79
J 2
(-1600 3200);
DISPLAY 0.936170 (-1600 3200);
PAINT GREEN (-1600 3200);
DISPLAY INVISIBLE (-1600 3200);
FORCEADD TAP..6
R 2
(900 4800);
FORCEPROP 3 LASTPIN (850 4800) SIG_NAME M_E_DQS_DN<14>
J 0
(860 4810);
DISPLAY 0.659574 (860 4810);
PAINT MONO (860 4810);
DISPLAY INVISIBLE (860 4810);
FORCEPROP 1 LASTPIN (850 4800) BN 14
J 2
(900 4810);
DISPLAY 0.617021 (900 4810);
PAINT PINK (900 4810);
FORCEPROP 2 LAST CDS_LIB mstr_standard
J 0
(900 4800);
DISPLAY 0.787234 (900 4800);
PAINT MONO (900 4800);
DISPLAY INVISIBLE (900 4800);
FORCEPROP 1 LAST BODY_TYPE PLUMBING
J 2
(900 4750);
DISPLAY 1.234043 (900 4750);
PAINT GREEN (900 4750);
DISPLAY INVISIBLE (900 4750);
FORCEPROP 1 LAST HDL_TAP TRUE
J 2
(575 4675);
DISPLAY 1.234043 (575 4675);
PAINT GREEN (575 4675);
DISPLAY INVISIBLE (575 4675);
FORCEPROP 1 LAST PATH I8
J 2
(900 4800);
DISPLAY 0.936170 (900 4800);
PAINT GREEN (900 4800);
DISPLAY INVISIBLE (900 4800);
FORCEADD TAP..6
R 2
(-1600 3300);
FORCEPROP 3 LASTPIN (-1650 3300) SIG_NAME M_E_DQ<30>
J 0
(-1640 3310);
DISPLAY 0.659574 (-1640 3310);
PAINT MONO (-1640 3310);
DISPLAY INVISIBLE (-1640 3310);
FORCEPROP 1 LASTPIN (-1650 3300) BN 30
J 2
(-1600 3310);
DISPLAY 0.617021 (-1600 3310);
PAINT PINK (-1600 3310);
FORCEPROP 2 LAST CDS_LIB mstr_standard
J 2
(-1600 3300);
DISPLAY 0.787234 (-1600 3300);
PAINT MONO (-1600 3300);
DISPLAY INVISIBLE (-1600 3300);
FORCEPROP 1 LAST BODY_TYPE PLUMBING
J 2
(-1600 3250);
DISPLAY 1.234043 (-1600 3250);
PAINT GREEN (-1600 3250);
DISPLAY INVISIBLE (-1600 3250);
FORCEPROP 1 LAST HDL_TAP TRUE
J 2
(-1925 3175);
DISPLAY 1.234043 (-1925 3175);
PAINT GREEN (-1925 3175);
DISPLAY INVISIBLE (-1925 3175);
FORCEPROP 1 LAST PATH I80
J 2
(-1600 3300);
DISPLAY 0.936170 (-1600 3300);
PAINT GREEN (-1600 3300);
DISPLAY INVISIBLE (-1600 3300);
FORCEADD TAP..6
R 2
(-1600 3250);
FORCEPROP 3 LASTPIN (-1650 3250) SIG_NAME M_E_DQ<31>
J 0
(-1640 3260);
DISPLAY 0.659574 (-1640 3260);
PAINT MONO (-1640 3260);
DISPLAY INVISIBLE (-1640 3260);
FORCEPROP 1 LASTPIN (-1650 3250) BN 31
J 2
(-1600 3260);
DISPLAY 0.617021 (-1600 3260);
PAINT PINK (-1600 3260);
FORCEPROP 2 LAST CDS_LIB mstr_standard
J 2
(-1600 3250);
DISPLAY 0.787234 (-1600 3250);
PAINT MONO (-1600 3250);
DISPLAY INVISIBLE (-1600 3250);
FORCEPROP 1 LAST BODY_TYPE PLUMBING
J 2
(-1600 3200);
DISPLAY 1.234043 (-1600 3200);
PAINT GREEN (-1600 3200);
DISPLAY INVISIBLE (-1600 3200);
FORCEPROP 1 LAST HDL_TAP TRUE
J 2
(-1925 3125);
DISPLAY 1.234043 (-1925 3125);
PAINT GREEN (-1925 3125);
DISPLAY INVISIBLE (-1925 3125);
FORCEPROP 1 LAST PATH I81
J 2
(-1600 3250);
DISPLAY 0.936170 (-1600 3250);
PAINT GREEN (-1600 3250);
DISPLAY INVISIBLE (-1600 3250);
FORCEADD TAP..6
R 2
(-1600 3100);
FORCEPROP 3 LASTPIN (-1650 3100) SIG_NAME M_E_DQ<26>
J 0
(-1640 3110);
DISPLAY 0.659574 (-1640 3110);
PAINT MONO (-1640 3110);
DISPLAY INVISIBLE (-1640 3110);
FORCEPROP 1 LASTPIN (-1650 3100) BN 26
J 2
(-1600 3110);
DISPLAY 0.617021 (-1600 3110);
PAINT PINK (-1600 3110);
FORCEPROP 2 LAST CDS_LIB mstr_standard
J 2
(-1600 3100);
DISPLAY 0.787234 (-1600 3100);
PAINT MONO (-1600 3100);
DISPLAY INVISIBLE (-1600 3100);
FORCEPROP 1 LAST BODY_TYPE PLUMBING
J 2
(-1600 3050);
DISPLAY 1.234043 (-1600 3050);
PAINT GREEN (-1600 3050);
DISPLAY INVISIBLE (-1600 3050);
FORCEPROP 1 LAST HDL_TAP TRUE
J 2
(-1925 2975);
DISPLAY 1.234043 (-1925 2975);
PAINT GREEN (-1925 2975);
DISPLAY INVISIBLE (-1925 2975);
FORCEPROP 1 LAST PATH I82
J 2
(-1600 3100);
DISPLAY 0.936170 (-1600 3100);
PAINT GREEN (-1600 3100);
DISPLAY INVISIBLE (-1600 3100);
FORCEADD TAP..6
R 2
(-1600 3150);
FORCEPROP 3 LASTPIN (-1650 3150) SIG_NAME M_E_DQ<29>
J 0
(-1640 3160);
DISPLAY 0.659574 (-1640 3160);
PAINT MONO (-1640 3160);
DISPLAY INVISIBLE (-1640 3160);
FORCEPROP 1 LASTPIN (-1650 3150) BN 29
J 2
(-1600 3160);
DISPLAY 0.617021 (-1600 3160);
PAINT PINK (-1600 3160);
FORCEPROP 2 LAST CDS_LIB mstr_standard
J 2
(-1600 3150);
DISPLAY 0.787234 (-1600 3150);
PAINT MONO (-1600 3150);
DISPLAY INVISIBLE (-1600 3150);
FORCEPROP 1 LAST BODY_TYPE PLUMBING
J 2
(-1600 3100);
DISPLAY 1.234043 (-1600 3100);
PAINT GREEN (-1600 3100);
DISPLAY INVISIBLE (-1600 3100);
FORCEPROP 1 LAST HDL_TAP TRUE
J 2
(-1925 3025);
DISPLAY 1.234043 (-1925 3025);
PAINT GREEN (-1925 3025);
DISPLAY INVISIBLE (-1925 3025);
FORCEPROP 1 LAST PATH I83
J 2
(-1600 3150);
DISPLAY 0.936170 (-1600 3150);
PAINT GREEN (-1600 3150);
DISPLAY INVISIBLE (-1600 3150);
FORCEADD TAP..6
R 2
(-1600 3050);
FORCEPROP 3 LASTPIN (-1650 3050) SIG_NAME M_E_DQ<27>
J 0
(-1640 3060);
DISPLAY 0.659574 (-1640 3060);
PAINT MONO (-1640 3060);
DISPLAY INVISIBLE (-1640 3060);
FORCEPROP 1 LASTPIN (-1650 3050) BN 27
J 2
(-1600 3060);
DISPLAY 0.617021 (-1600 3060);
PAINT PINK (-1600 3060);
FORCEPROP 2 LAST CDS_LIB mstr_standard
J 2
(-1600 3050);
DISPLAY 0.787234 (-1600 3050);
PAINT MONO (-1600 3050);
DISPLAY INVISIBLE (-1600 3050);
FORCEPROP 1 LAST BODY_TYPE PLUMBING
J 2
(-1600 3000);
DISPLAY 1.234043 (-1600 3000);
PAINT GREEN (-1600 3000);
DISPLAY INVISIBLE (-1600 3000);
FORCEPROP 1 LAST HDL_TAP TRUE
J 2
(-1925 2925);
DISPLAY 1.234043 (-1925 2925);
PAINT GREEN (-1925 2925);
DISPLAY INVISIBLE (-1925 2925);
FORCEPROP 1 LAST PATH I84
J 2
(-1600 3050);
DISPLAY 0.936170 (-1600 3050);
PAINT GREEN (-1600 3050);
DISPLAY INVISIBLE (-1600 3050);
FORCEADD TAP..6
R 2
(-1600 2950);
FORCEPROP 3 LASTPIN (-1650 2950) SIG_NAME M_E_DQ<25>
J 0
(-1640 2960);
DISPLAY 0.659574 (-1640 2960);
PAINT MONO (-1640 2960);
DISPLAY INVISIBLE (-1640 2960);
FORCEPROP 1 LASTPIN (-1650 2950) BN 25
J 2
(-1600 2960);
DISPLAY 0.617021 (-1600 2960);
PAINT PINK (-1600 2960);
FORCEPROP 2 LAST CDS_LIB mstr_standard
J 2
(-1600 2950);
DISPLAY 0.787234 (-1600 2950);
PAINT MONO (-1600 2950);
DISPLAY INVISIBLE (-1600 2950);
FORCEPROP 1 LAST BODY_TYPE PLUMBING
J 2
(-1600 2900);
DISPLAY 1.234043 (-1600 2900);
PAINT GREEN (-1600 2900);
DISPLAY INVISIBLE (-1600 2900);
FORCEPROP 1 LAST HDL_TAP TRUE
J 2
(-1925 2825);
DISPLAY 1.234043 (-1925 2825);
PAINT GREEN (-1925 2825);
DISPLAY INVISIBLE (-1925 2825);
FORCEPROP 1 LAST PATH I85
J 2
(-1600 2950);
DISPLAY 0.936170 (-1600 2950);
PAINT GREEN (-1600 2950);
DISPLAY INVISIBLE (-1600 2950);
FORCEADD TAP..6
R 2
(-1600 3000);
FORCEPROP 3 LASTPIN (-1650 3000) SIG_NAME M_E_DQ<24>
J 0
(-1640 3010);
DISPLAY 0.659574 (-1640 3010);
PAINT MONO (-1640 3010);
DISPLAY INVISIBLE (-1640 3010);
FORCEPROP 1 LASTPIN (-1650 3000) BN 24
J 2
(-1600 3010);
DISPLAY 0.617021 (-1600 3010);
PAINT PINK (-1600 3010);
FORCEPROP 2 LAST CDS_LIB mstr_standard
J 2
(-1600 3000);
DISPLAY 0.787234 (-1600 3000);
PAINT MONO (-1600 3000);
DISPLAY INVISIBLE (-1600 3000);
FORCEPROP 1 LAST BODY_TYPE PLUMBING
J 2
(-1600 2950);
DISPLAY 1.234043 (-1600 2950);
PAINT GREEN (-1600 2950);
DISPLAY INVISIBLE (-1600 2950);
FORCEPROP 1 LAST HDL_TAP TRUE
J 2
(-1925 2875);
DISPLAY 1.234043 (-1925 2875);
PAINT GREEN (-1925 2875);
DISPLAY INVISIBLE (-1925 2875);
FORCEPROP 1 LAST PATH I86
J 2
(-1600 3000);
DISPLAY 0.936170 (-1600 3000);
PAINT GREEN (-1600 3000);
DISPLAY INVISIBLE (-1600 3000);
FORCEADD TAP..6
R 2
(-1600 2850);
FORCEPROP 3 LASTPIN (-1650 2850) SIG_NAME M_E_DQ<23>
J 0
(-1640 2860);
DISPLAY 0.659574 (-1640 2860);
PAINT MONO (-1640 2860);
DISPLAY INVISIBLE (-1640 2860);
FORCEPROP 1 LASTPIN (-1650 2850) BN 23
J 2
(-1600 2860);
DISPLAY 0.617021 (-1600 2860);
PAINT PINK (-1600 2860);
FORCEPROP 2 LAST CDS_LIB mstr_standard
J 2
(-1600 2850);
DISPLAY 0.787234 (-1600 2850);
PAINT MONO (-1600 2850);
DISPLAY INVISIBLE (-1600 2850);
FORCEPROP 1 LAST BODY_TYPE PLUMBING
J 2
(-1600 2800);
DISPLAY 1.234043 (-1600 2800);
PAINT GREEN (-1600 2800);
DISPLAY INVISIBLE (-1600 2800);
FORCEPROP 1 LAST HDL_TAP TRUE
J 2
(-1925 2725);
DISPLAY 1.234043 (-1925 2725);
PAINT GREEN (-1925 2725);
DISPLAY INVISIBLE (-1925 2725);
FORCEPROP 1 LAST PATH I87
J 2
(-1600 2850);
DISPLAY 0.936170 (-1600 2850);
PAINT GREEN (-1600 2850);
DISPLAY INVISIBLE (-1600 2850);
FORCEADD TAP..6
R 2
(-1600 2900);
FORCEPROP 3 LASTPIN (-1650 2900) SIG_NAME M_E_DQ<22>
J 0
(-1640 2910);
DISPLAY 0.659574 (-1640 2910);
PAINT MONO (-1640 2910);
DISPLAY INVISIBLE (-1640 2910);
FORCEPROP 1 LASTPIN (-1650 2900) BN 22
J 2
(-1600 2910);
DISPLAY 0.617021 (-1600 2910);
PAINT PINK (-1600 2910);
FORCEPROP 2 LAST CDS_LIB mstr_standard
J 2
(-1600 2900);
DISPLAY 0.787234 (-1600 2900);
PAINT MONO (-1600 2900);
DISPLAY INVISIBLE (-1600 2900);
FORCEPROP 1 LAST BODY_TYPE PLUMBING
J 2
(-1600 2850);
DISPLAY 1.234043 (-1600 2850);
PAINT GREEN (-1600 2850);
DISPLAY INVISIBLE (-1600 2850);
FORCEPROP 1 LAST HDL_TAP TRUE
J 2
(-1925 2775);
DISPLAY 1.234043 (-1925 2775);
PAINT GREEN (-1925 2775);
DISPLAY INVISIBLE (-1925 2775);
FORCEPROP 1 LAST PATH I88
J 2
(-1600 2900);
DISPLAY 0.936170 (-1600 2900);
PAINT GREEN (-1600 2900);
DISPLAY INVISIBLE (-1600 2900);
FORCEADD TAP..6
R 2
(-1600 2800);
FORCEPROP 3 LASTPIN (-1650 2800) SIG_NAME M_E_DQ<20>
J 0
(-1640 2810);
DISPLAY 0.659574 (-1640 2810);
PAINT MONO (-1640 2810);
DISPLAY INVISIBLE (-1640 2810);
FORCEPROP 1 LASTPIN (-1650 2800) BN 20
J 2
(-1600 2810);
DISPLAY 0.617021 (-1600 2810);
PAINT PINK (-1600 2810);
FORCEPROP 2 LAST CDS_LIB mstr_standard
J 2
(-1600 2800);
DISPLAY 0.787234 (-1600 2800);
PAINT MONO (-1600 2800);
DISPLAY INVISIBLE (-1600 2800);
FORCEPROP 1 LAST BODY_TYPE PLUMBING
J 2
(-1600 2750);
DISPLAY 1.234043 (-1600 2750);
PAINT GREEN (-1600 2750);
DISPLAY INVISIBLE (-1600 2750);
FORCEPROP 1 LAST HDL_TAP TRUE
J 2
(-1925 2675);
DISPLAY 1.234043 (-1925 2675);
PAINT GREEN (-1925 2675);
DISPLAY INVISIBLE (-1925 2675);
FORCEPROP 1 LAST PATH I89
J 2
(-1600 2800);
DISPLAY 0.936170 (-1600 2800);
PAINT GREEN (-1600 2800);
DISPLAY INVISIBLE (-1600 2800);
FORCEADD TAP..6
R 2
(900 4600);
FORCEPROP 3 LASTPIN (850 4600) SIG_NAME M_E_DQS_DN<12>
J 0
(860 4610);
DISPLAY 0.659574 (860 4610);
PAINT MONO (860 4610);
DISPLAY INVISIBLE (860 4610);
FORCEPROP 1 LASTPIN (850 4600) BN 12
J 2
(900 4610);
DISPLAY 0.617021 (900 4610);
PAINT PINK (900 4610);
FORCEPROP 2 LAST CDS_LIB mstr_standard
J 0
(900 4600);
DISPLAY 0.787234 (900 4600);
PAINT MONO (900 4600);
DISPLAY INVISIBLE (900 4600);
FORCEPROP 1 LAST BODY_TYPE PLUMBING
J 2
(900 4550);
DISPLAY 1.234043 (900 4550);
PAINT GREEN (900 4550);
DISPLAY INVISIBLE (900 4550);
FORCEPROP 1 LAST HDL_TAP TRUE
J 2
(575 4475);
DISPLAY 1.234043 (575 4475);
PAINT GREEN (575 4475);
DISPLAY INVISIBLE (575 4475);
FORCEPROP 1 LAST PATH I9
J 2
(900 4600);
DISPLAY 0.936170 (900 4600);
PAINT GREEN (900 4600);
DISPLAY INVISIBLE (900 4600);
FORCEADD TAP..6
R 2
(-1600 2750);
FORCEPROP 3 LASTPIN (-1650 2750) SIG_NAME M_E_DQ<21>
J 0
(-1640 2760);
DISPLAY 0.659574 (-1640 2760);
PAINT MONO (-1640 2760);
DISPLAY INVISIBLE (-1640 2760);
FORCEPROP 1 LASTPIN (-1650 2750) BN 21
J 2
(-1600 2760);
DISPLAY 0.617021 (-1600 2760);
PAINT PINK (-1600 2760);
FORCEPROP 2 LAST CDS_LIB mstr_standard
J 2
(-1600 2750);
DISPLAY 0.787234 (-1600 2750);
PAINT MONO (-1600 2750);
DISPLAY INVISIBLE (-1600 2750);
FORCEPROP 1 LAST BODY_TYPE PLUMBING
J 2
(-1600 2700);
DISPLAY 1.234043 (-1600 2700);
PAINT GREEN (-1600 2700);
DISPLAY INVISIBLE (-1600 2700);
FORCEPROP 1 LAST HDL_TAP TRUE
J 2
(-1925 2625);
DISPLAY 1.234043 (-1925 2625);
PAINT GREEN (-1925 2625);
DISPLAY INVISIBLE (-1925 2625);
FORCEPROP 1 LAST PATH I90
J 2
(-1600 2750);
DISPLAY 0.936170 (-1600 2750);
PAINT GREEN (-1600 2750);
DISPLAY INVISIBLE (-1600 2750);
FORCEADD TAP..6
R 2
(-1600 2700);
FORCEPROP 3 LASTPIN (-1650 2700) SIG_NAME M_E_DQ<18>
J 0
(-1640 2710);
DISPLAY 0.659574 (-1640 2710);
PAINT MONO (-1640 2710);
DISPLAY INVISIBLE (-1640 2710);
FORCEPROP 1 LASTPIN (-1650 2700) BN 18
J 2
(-1600 2710);
DISPLAY 0.617021 (-1600 2710);
PAINT PINK (-1600 2710);
FORCEPROP 2 LAST CDS_LIB mstr_standard
J 2
(-1600 2700);
DISPLAY 0.787234 (-1600 2700);
PAINT MONO (-1600 2700);
DISPLAY INVISIBLE (-1600 2700);
FORCEPROP 1 LAST BODY_TYPE PLUMBING
J 2
(-1600 2650);
DISPLAY 1.234043 (-1600 2650);
PAINT GREEN (-1600 2650);
DISPLAY INVISIBLE (-1600 2650);
FORCEPROP 1 LAST HDL_TAP TRUE
J 2
(-1925 2575);
DISPLAY 1.234043 (-1925 2575);
PAINT GREEN (-1925 2575);
DISPLAY INVISIBLE (-1925 2575);
FORCEPROP 1 LAST PATH I91
J 2
(-1600 2700);
DISPLAY 0.936170 (-1600 2700);
PAINT GREEN (-1600 2700);
DISPLAY INVISIBLE (-1600 2700);
FORCEADD TAP..6
R 2
(-1600 2650);
FORCEPROP 3 LASTPIN (-1650 2650) SIG_NAME M_E_DQ<19>
J 0
(-1640 2660);
DISPLAY 0.659574 (-1640 2660);
PAINT MONO (-1640 2660);
DISPLAY INVISIBLE (-1640 2660);
FORCEPROP 1 LASTPIN (-1650 2650) BN 19
J 2
(-1600 2660);
DISPLAY 0.617021 (-1600 2660);
PAINT PINK (-1600 2660);
FORCEPROP 2 LAST CDS_LIB mstr_standard
J 2
(-1600 2650);
DISPLAY 0.787234 (-1600 2650);
PAINT MONO (-1600 2650);
DISPLAY INVISIBLE (-1600 2650);
FORCEPROP 1 LAST BODY_TYPE PLUMBING
J 2
(-1600 2600);
DISPLAY 1.234043 (-1600 2600);
PAINT GREEN (-1600 2600);
DISPLAY INVISIBLE (-1600 2600);
FORCEPROP 1 LAST HDL_TAP TRUE
J 2
(-1925 2525);
DISPLAY 1.234043 (-1925 2525);
PAINT GREEN (-1925 2525);
DISPLAY INVISIBLE (-1925 2525);
FORCEPROP 1 LAST PATH I92
J 2
(-1600 2650);
DISPLAY 0.936170 (-1600 2650);
PAINT GREEN (-1600 2650);
DISPLAY INVISIBLE (-1600 2650);
FORCEADD TAP..6
R 2
(-1600 2550);
FORCEPROP 3 LASTPIN (-1650 2550) SIG_NAME M_E_DQ<17>
J 0
(-1640 2560);
DISPLAY 0.659574 (-1640 2560);
PAINT MONO (-1640 2560);
DISPLAY INVISIBLE (-1640 2560);
FORCEPROP 1 LASTPIN (-1650 2550) BN 17
J 2
(-1600 2560);
DISPLAY 0.617021 (-1600 2560);
PAINT PINK (-1600 2560);
FORCEPROP 2 LAST CDS_LIB mstr_standard
J 2
(-1600 2550);
DISPLAY 0.787234 (-1600 2550);
PAINT MONO (-1600 2550);
DISPLAY INVISIBLE (-1600 2550);
FORCEPROP 1 LAST BODY_TYPE PLUMBING
J 2
(-1600 2500);
DISPLAY 1.234043 (-1600 2500);
PAINT GREEN (-1600 2500);
DISPLAY INVISIBLE (-1600 2500);
FORCEPROP 1 LAST HDL_TAP TRUE
J 2
(-1925 2425);
DISPLAY 1.234043 (-1925 2425);
PAINT GREEN (-1925 2425);
DISPLAY INVISIBLE (-1925 2425);
FORCEPROP 1 LAST PATH I93
J 2
(-1600 2550);
DISPLAY 0.936170 (-1600 2550);
PAINT GREEN (-1600 2550);
DISPLAY INVISIBLE (-1600 2550);
FORCEADD TAP..6
R 2
(-1600 2600);
FORCEPROP 3 LASTPIN (-1650 2600) SIG_NAME M_E_DQ<16>
J 0
(-1640 2610);
DISPLAY 0.659574 (-1640 2610);
PAINT MONO (-1640 2610);
DISPLAY INVISIBLE (-1640 2610);
FORCEPROP 1 LASTPIN (-1650 2600) BN 16
J 2
(-1600 2610);
DISPLAY 0.617021 (-1600 2610);
PAINT PINK (-1600 2610);
FORCEPROP 2 LAST CDS_LIB mstr_standard
J 2
(-1600 2600);
DISPLAY 0.787234 (-1600 2600);
PAINT MONO (-1600 2600);
DISPLAY INVISIBLE (-1600 2600);
FORCEPROP 1 LAST BODY_TYPE PLUMBING
J 2
(-1600 2550);
DISPLAY 1.234043 (-1600 2550);
PAINT GREEN (-1600 2550);
DISPLAY INVISIBLE (-1600 2550);
FORCEPROP 1 LAST HDL_TAP TRUE
J 2
(-1925 2475);
DISPLAY 1.234043 (-1925 2475);
PAINT GREEN (-1925 2475);
DISPLAY INVISIBLE (-1925 2475);
FORCEPROP 1 LAST PATH I94
J 2
(-1600 2600);
DISPLAY 0.936170 (-1600 2600);
PAINT GREEN (-1600 2600);
DISPLAY INVISIBLE (-1600 2600);
FORCEADD TAP..6
R 2
(-1600 2500);
FORCEPROP 3 LASTPIN (-1650 2500) SIG_NAME M_E_DQ<14>
J 0
(-1640 2510);
DISPLAY 0.659574 (-1640 2510);
PAINT MONO (-1640 2510);
DISPLAY INVISIBLE (-1640 2510);
FORCEPROP 1 LASTPIN (-1650 2500) BN 14
J 2
(-1600 2510);
DISPLAY 0.617021 (-1600 2510);
PAINT PINK (-1600 2510);
FORCEPROP 2 LAST CDS_LIB mstr_standard
J 2
(-1600 2500);
DISPLAY 0.787234 (-1600 2500);
PAINT MONO (-1600 2500);
DISPLAY INVISIBLE (-1600 2500);
FORCEPROP 1 LAST BODY_TYPE PLUMBING
J 2
(-1600 2450);
DISPLAY 1.234043 (-1600 2450);
PAINT GREEN (-1600 2450);
DISPLAY INVISIBLE (-1600 2450);
FORCEPROP 1 LAST HDL_TAP TRUE
J 2
(-1925 2375);
DISPLAY 1.234043 (-1925 2375);
PAINT GREEN (-1925 2375);
DISPLAY INVISIBLE (-1925 2375);
FORCEPROP 1 LAST PATH I95
J 2
(-1600 2500);
DISPLAY 0.936170 (-1600 2500);
PAINT GREEN (-1600 2500);
DISPLAY INVISIBLE (-1600 2500);
FORCEADD TAP..6
R 2
(-1600 2450);
FORCEPROP 3 LASTPIN (-1650 2450) SIG_NAME M_E_DQ<15>
J 0
(-1640 2460);
DISPLAY 0.659574 (-1640 2460);
PAINT MONO (-1640 2460);
DISPLAY INVISIBLE (-1640 2460);
FORCEPROP 1 LASTPIN (-1650 2450) BN 15
J 2
(-1600 2460);
DISPLAY 0.617021 (-1600 2460);
PAINT PINK (-1600 2460);
FORCEPROP 2 LAST CDS_LIB mstr_standard
J 2
(-1600 2450);
DISPLAY 0.787234 (-1600 2450);
PAINT MONO (-1600 2450);
DISPLAY INVISIBLE (-1600 2450);
FORCEPROP 1 LAST BODY_TYPE PLUMBING
J 2
(-1600 2400);
DISPLAY 1.234043 (-1600 2400);
PAINT GREEN (-1600 2400);
DISPLAY INVISIBLE (-1600 2400);
FORCEPROP 1 LAST HDL_TAP TRUE
J 2
(-1925 2325);
DISPLAY 1.234043 (-1925 2325);
PAINT GREEN (-1925 2325);
DISPLAY INVISIBLE (-1925 2325);
FORCEPROP 1 LAST PATH I96
J 2
(-1600 2450);
DISPLAY 0.936170 (-1600 2450);
PAINT GREEN (-1600 2450);
DISPLAY INVISIBLE (-1600 2450);
FORCEADD TAP..6
R 2
(-1600 2350);
FORCEPROP 3 LASTPIN (-1650 2350) SIG_NAME M_E_DQ<13>
J 0
(-1640 2360);
DISPLAY 0.659574 (-1640 2360);
PAINT MONO (-1640 2360);
DISPLAY INVISIBLE (-1640 2360);
FORCEPROP 1 LASTPIN (-1650 2350) BN 13
J 2
(-1600 2360);
DISPLAY 0.617021 (-1600 2360);
PAINT PINK (-1600 2360);
FORCEPROP 2 LAST CDS_LIB mstr_standard
J 2
(-1600 2350);
DISPLAY 0.787234 (-1600 2350);
PAINT MONO (-1600 2350);
DISPLAY INVISIBLE (-1600 2350);
FORCEPROP 1 LAST BODY_TYPE PLUMBING
J 2
(-1600 2300);
DISPLAY 1.234043 (-1600 2300);
PAINT GREEN (-1600 2300);
DISPLAY INVISIBLE (-1600 2300);
FORCEPROP 1 LAST HDL_TAP TRUE
J 2
(-1925 2225);
DISPLAY 1.234043 (-1925 2225);
PAINT GREEN (-1925 2225);
DISPLAY INVISIBLE (-1925 2225);
FORCEPROP 1 LAST PATH I97
J 2
(-1600 2350);
DISPLAY 0.936170 (-1600 2350);
PAINT GREEN (-1600 2350);
DISPLAY INVISIBLE (-1600 2350);
FORCEADD TAP..6
R 2
(-1600 2400);
FORCEPROP 3 LASTPIN (-1650 2400) SIG_NAME M_E_DQ<12>
J 0
(-1640 2410);
DISPLAY 0.659574 (-1640 2410);
PAINT MONO (-1640 2410);
DISPLAY INVISIBLE (-1640 2410);
FORCEPROP 1 LASTPIN (-1650 2400) BN 12
J 2
(-1600 2410);
DISPLAY 0.617021 (-1600 2410);
PAINT PINK (-1600 2410);
FORCEPROP 2 LAST CDS_LIB mstr_standard
J 2
(-1600 2400);
DISPLAY 0.787234 (-1600 2400);
PAINT MONO (-1600 2400);
DISPLAY INVISIBLE (-1600 2400);
FORCEPROP 1 LAST BODY_TYPE PLUMBING
J 2
(-1600 2350);
DISPLAY 1.234043 (-1600 2350);
PAINT GREEN (-1600 2350);
DISPLAY INVISIBLE (-1600 2350);
FORCEPROP 1 LAST HDL_TAP TRUE
J 2
(-1925 2275);
DISPLAY 1.234043 (-1925 2275);
PAINT GREEN (-1925 2275);
DISPLAY INVISIBLE (-1925 2275);
FORCEPROP 1 LAST PATH I98
J 2
(-1600 2400);
DISPLAY 0.936170 (-1600 2400);
PAINT GREEN (-1600 2400);
DISPLAY INVISIBLE (-1600 2400);
FORCEADD TAP..6
R 2
(-1600 2300);
FORCEPROP 3 LASTPIN (-1650 2300) SIG_NAME M_E_DQ<10>
J 0
(-1640 2310);
DISPLAY 0.659574 (-1640 2310);
PAINT MONO (-1640 2310);
DISPLAY INVISIBLE (-1640 2310);
FORCEPROP 1 LASTPIN (-1650 2300) BN 10
J 2
(-1600 2310);
DISPLAY 0.617021 (-1600 2310);
PAINT PINK (-1600 2310);
FORCEPROP 2 LAST CDS_LIB mstr_standard
J 2
(-1600 2300);
DISPLAY 0.787234 (-1600 2300);
PAINT MONO (-1600 2300);
DISPLAY INVISIBLE (-1600 2300);
FORCEPROP 1 LAST BODY_TYPE PLUMBING
J 2
(-1600 2250);
DISPLAY 1.234043 (-1600 2250);
PAINT GREEN (-1600 2250);
DISPLAY INVISIBLE (-1600 2250);
FORCEPROP 1 LAST HDL_TAP TRUE
J 2
(-1925 2175);
DISPLAY 1.234043 (-1925 2175);
PAINT GREEN (-1925 2175);
DISPLAY INVISIBLE (-1925 2175);
FORCEPROP 1 LAST PATH I99
J 2
(-1600 2300);
DISPLAY 0.936170 (-1600 2300);
PAINT GREEN (-1600 2300);
DISPLAY INVISIBLE (-1600 2300);
FORCEADD INTEL_CORP_BPAGE..1
(2650 500);
FORCEPROP 1 LAST CDS_CON_LAST_MODIFIED Fri Jun 16 17:48:20 2017
J 0
(1225 825);
DISPLAY 0.787234 (1225 825);
PAINT ORANGE (1225 825);
DISPLAY INVISIBLE (1225 825);
FORCEPROP 1 LAST CUSTOM_TXT_CDS <CURRENT_DESIGN_SHEET> OF <TOTAL_DESIGN_SHEETS>
J 0
(2150 525);
PAINT ORANGE (2150 525);
FORCEPROP 1 LAST CUSTOM_TXT_CDS <CON_LAST_MODIFIED>
J 0
(-1350 600);
PAINT ORANGE (-1350 600);
FORCEPROP 2 LAST CUSTOM_TXT_CDS <XR_PAGE_TITLE>
J 0
(-5240 5750);
DISPLAY 0.638298 (-5240 5750);
PAINT PINK (-5240 5750);
DISPLAY INVISIBLE (-5240 5750);
FORCEPROP 1 LAST SCH_TITLE CPU0 DDR4 CH E DIMM0
J 0
(-5300 550);
DISPLAY 1.212766 (-5300 550);
PAINT WHITE (-5300 550);
FORCEPROP 2 LAST CDS_LIB mstr_symbols
J 0
(2650 500);
DISPLAY 0.787234 (2650 500);
PAINT MONO (2650 500);
DISPLAY INVISIBLE (2650 500);
FORCEPROP 2 LAST PAGE_BORDER TRUE
J 0
(-5240 5750);
DISPLAY 0.680851 (-5240 5750);
PAINT PINK (-5240 5750);
DISPLAY INVISIBLE (-5240 5750);
FORCEPROP 1 LAST COMMENT_BODY TRUE
J 0
(2660 510);
DISPLAY 0.382979 (2660 510);
PAINT GREEN (2660 510);
DISPLAY INVISIBLE (2660 510);
FORCEPROP 2 LAST CDS_XR_PAGE_TITLE CR-51 : @BASEBOARD_FAB2_LIB.BASEBOARD_FAB2(SCH_1):PAGE51
J 0
(-5240 5750);
DISPLAY 0.638298 (-5240 5750);
PAINT PINK (-5240 5750);
DISPLAY INVISIBLE (-5240 5750);
FORCEADD BOM_NOTE..1
(-5025 5300);
FORCEPROP 0 LAST L1 STUFF FOR SKU A & B
J 0
(-5175 5200);
DISPLAY 1.063830 (-5175 5200);
PAINT WHITE (-5175 5200);
FORCEPROP 2 LAST BOM_COST SB
J 0
(-5175 5275);
DISPLAY 1.361702 (-5175 5275);
PAINT ORANGE (-5175 5275);
DISPLAY INVISIBLE (-5175 5275);
FORCEPROP 2 LAST CDS_LIB mstr_symbols
J 0
(-5025 5300);
PAINT ORANGE (-5025 5300);
DISPLAY INVISIBLE (-5025 5300);
FORCEPROP 1 LAST COMMENT_BODY TRUE
J 0
(-5000 5400);
DISPLAY 1.319149 (-5000 5400);
PAINT ORANGE (-5000 5400);
DISPLAY INVISIBLE (-5000 5400);
FORCEPROP 2 LAST ROOM SB_HEADERS
J 0
(-5175 5275);
DISPLAY 1.361702 (-5175 5275);
PAINT ORANGE (-5175 5275);
DISPLAY INVISIBLE (-5175 5275);
WIRE 16 -1 (-1225 2550)(-1225 2450);
WIRE 16 -1 (-1225 2450)(-850 2450);
WIRE 16 -1 (-850 2400)(-850 2450);
WIRE 16 -1 (-850 2450)(-650 2450);
WIRE 16 -1 (-850 2350)(-850 2400);
WIRE 16 -1 (-850 2400)(-650 2400);
WIRE 16 -1 (-850 2300)(-850 2350);
WIRE 16 -1 (-850 2350)(-650 2350);
WIRE 16 -1 (-850 2250)(-850 2300);
WIRE 16 -1 (-850 2300)(-650 2300);
WIRE 16 -1 (-850 2200)(-850 2250);
WIRE 16 -1 (-850 2250)(-650 2250);
WIRE 16 -1 (-850 2150)(-850 2200);
WIRE 16 -1 (-850 2200)(-650 2200);
WIRE 16 -1 (-850 2100)(-850 2150);
WIRE 16 -1 (-850 2150)(-650 2150);
WIRE 16 -1 (-850 2050)(-850 2100);
WIRE 16 -1 (-850 2100)(-650 2100);
WIRE 16 -1 (-850 2000)(-850 2050);
WIRE 16 -1 (-850 2050)(-650 2050);
WIRE 16 -1 (-850 1950)(-850 2000);
WIRE 16 -1 (-850 2000)(-650 2000);
WIRE 16 -1 (-850 1900)(-850 1950);
WIRE 16 -1 (-850 1950)(-650 1950);
WIRE 16 -1 (-850 1850)(-850 1900);
WIRE 16 -1 (-850 1900)(-650 1900);
WIRE 16 -1 (-850 1800)(-850 1850);
WIRE 16 -1 (-850 1850)(-650 1850);
WIRE 16 -1 (-850 1750)(-850 1800);
WIRE 16 -1 (-850 1800)(-650 1800);
WIRE 16 -1 (-850 1700)(-850 1750);
WIRE 16 -1 (-850 1750)(-650 1750);
WIRE 16 -1 (-850 1650)(-850 1700);
WIRE 16 -1 (-850 1700)(-650 1700);
WIRE 16 -1 (-850 1600)(-850 1650);
WIRE 16 -1 (-850 1650)(-650 1650);
WIRE 16 -1 (-850 1550)(-850 1600);
WIRE 16 -1 (-850 1600)(-650 1600);
WIRE 16 -1 (-850 1500)(-850 1550);
WIRE 16 -1 (-850 1550)(-650 1550);
WIRE 16 -1 (-850 1450)(-850 1500);
WIRE 16 -1 (-850 1500)(-650 1500);
WIRE 16 -1 (-850 1400)(-850 1450);
WIRE 16 -1 (-850 1450)(-650 1450);
WIRE 16 -1 (-850 1350)(-850 1400);
WIRE 16 -1 (-850 1400)(-650 1400);
WIRE 16 -1 (-850 1300)(-850 1350);
WIRE 16 -1 (-850 1350)(-650 1350);
WIRE 16 -1 (-850 1250)(-850 1300);
WIRE 16 -1 (-850 1300)(-650 1300);
WIRE 16 -1 (-850 1250)(-850 1200);
WIRE 16 -1 (-850 1250)(-650 1250);
WIRE 16 -1 (-850 1200)(-650 1200);
WIRE 16 -1 (2500 1250)(2500 1350);
WIRE 16 -1 (2500 1350)(2500 1400);
WIRE 16 -1 (2500 1350)(2300 1350);
WIRE 16 -1 (2500 1400)(2500 1450);
WIRE 16 -1 (2500 1400)(2300 1400);
WIRE 16 -1 (2500 1450)(2500 1500);
WIRE 16 -1 (2500 1450)(2300 1450);
WIRE 16 -1 (2500 1500)(2500 1550);
WIRE 16 -1 (2500 1500)(2300 1500);
WIRE 16 -1 (2500 1550)(2500 1600);
WIRE 16 -1 (2500 1550)(2300 1550);
WIRE 16 -1 (2500 1600)(2500 1650);
WIRE 16 -1 (2500 1600)(2300 1600);
WIRE 16 -1 (2500 1650)(2500 1700);
WIRE 16 -1 (2500 1650)(2300 1650);
WIRE 16 -1 (2500 1700)(2500 1750);
WIRE 16 -1 (2500 1700)(2300 1700);
WIRE 16 -1 (2500 1750)(2500 1800);
WIRE 16 -1 (2500 1750)(2300 1750);
WIRE 16 -1 (2500 1800)(2500 1850);
WIRE 16 -1 (2500 1800)(2300 1800);
WIRE 16 -1 (2500 1850)(2500 1900);
WIRE 16 -1 (2500 1850)(2300 1850);
WIRE 16 -1 (2500 1900)(2500 1950);
WIRE 16 -1 (2500 1900)(2300 1900);
WIRE 16 -1 (2500 1950)(2500 2000);
WIRE 16 -1 (2500 1950)(2300 1950);
WIRE 16 -1 (2500 2000)(2500 2050);
WIRE 16 -1 (2500 2000)(2300 2000);
WIRE 16 -1 (2500 2050)(2500 2100);
WIRE 16 -1 (2500 2050)(2300 2050);
WIRE 16 -1 (2500 2100)(2500 2150);
WIRE 16 -1 (2500 2100)(2300 2100);
WIRE 16 -1 (2500 2150)(2500 2200);
WIRE 16 -1 (2500 2150)(2300 2150);
WIRE 16 -1 (2500 2200)(2500 2250);
WIRE 16 -1 (2500 2200)(2300 2200);
WIRE 16 -1 (2500 2250)(2500 2300);
WIRE 16 -1 (2500 2250)(2300 2250);
WIRE 16 -1 (2500 2300)(2500 2350);
WIRE 16 -1 (2500 2300)(2300 2300);
WIRE 16 -1 (2500 2350)(2500 2400);
WIRE 16 -1 (2500 2350)(2300 2350);
WIRE 16 -1 (2500 2400)(2500 2450);
WIRE 16 -1 (2500 2400)(2300 2400);
WIRE 16 -1 (2500 2450)(2500 2500);
WIRE 16 -1 (2500 2450)(2300 2450);
WIRE 16 -1 (2500 2500)(2500 2550);
WIRE 16 -1 (2500 2500)(2300 2500);
WIRE 16 -1 (2500 2550)(2500 2600);
WIRE 16 -1 (2500 2550)(2300 2550);
WIRE 16 -1 (2500 2600)(2500 2650);
WIRE 16 -1 (2500 2600)(2300 2600);
WIRE 16 -1 (2500 2650)(2500 2700);
WIRE 16 -1 (2500 2650)(2300 2650);
WIRE 16 -1 (2500 2700)(2500 2750);
WIRE 16 -1 (2500 2700)(2300 2700);
WIRE 16 -1 (2500 2750)(2500 2800);
WIRE 16 -1 (2500 2750)(2300 2750);
WIRE 16 -1 (2500 2800)(2500 2850);
WIRE 16 -1 (2500 2800)(2300 2800);
WIRE 16 -1 (2500 2850)(2500 2900);
WIRE 16 -1 (2500 2850)(2300 2850);
WIRE 16 -1 (2500 2900)(2500 2950);
WIRE 16 -1 (2500 2900)(2300 2900);
WIRE 16 -1 (2500 2950)(2500 3000);
WIRE 16 -1 (2500 2950)(2300 2950);
WIRE 16 -1 (2500 3000)(2500 3050);
WIRE 16 -1 (2500 3000)(2300 3000);
WIRE 16 -1 (2500 3050)(2500 3100);
WIRE 16 -1 (2500 3050)(2300 3050);
WIRE 16 -1 (2500 3100)(2500 3150);
WIRE 16 -1 (2500 3100)(2300 3100);
WIRE 16 -1 (2500 3150)(2500 3200);
WIRE 16 -1 (2500 3150)(2300 3150);
WIRE 16 -1 (2500 3200)(2500 3250);
WIRE 16 -1 (2500 3200)(2300 3200);
WIRE 16 -1 (2500 3250)(2500 3300);
WIRE 16 -1 (2500 3250)(2300 3250);
WIRE 16 -1 (2500 3300)(2500 3350);
WIRE 16 -1 (2500 3300)(2300 3300);
WIRE 16 -1 (2500 3350)(2500 3400);
WIRE 16 -1 (2500 3350)(2300 3350);
WIRE 16 -1 (2500 3400)(2500 3450);
WIRE 16 -1 (2500 3400)(2300 3400);
WIRE 16 -1 (2500 3450)(2500 3500);
WIRE 16 -1 (2500 3450)(2300 3450);
WIRE 16 -1 (2500 3500)(2500 3550);
WIRE 16 -1 (2500 3500)(2300 3500);
WIRE 16 -1 (2500 3550)(2500 3600);
WIRE 16 -1 (2500 3550)(2300 3550);
WIRE 16 -1 (2500 3600)(2500 3650);
WIRE 16 -1 (2500 3600)(2300 3600);
WIRE 16 -1 (2500 3650)(2300 3650);
WIRE 16 -1 (-1000 2700)(-1000 2600);
WIRE 16 -1 (-1000 2600)(-850 2600);
WIRE 16 -1 (-850 2550)(-850 2600);
WIRE 16 -1 (-850 2600)(-650 2600);
WIRE 16 -1 (-650 2550)(-850 2550);
WIRE 16 -1 (-5200 1950)(-5200 1850);
WIRE 16 -1 (-3250 1950)(-5200 1950);
WIRE 16 -1 (-3250 2050)(-3250 1950);
WIRE 16 -1 (-2850 1950)(-3250 1950);
WIRE 16 -1 (-2850 2050)(-3250 2050);
WIRE 16 -1 (-4650 1350)(-4650 1450);
WIRE 16 -1 (-850 3000)(-850 2900);
WIRE 16 -1 (-850 2900)(-850 2850);
WIRE 16 -1 (-850 2900)(-650 2900);
WIRE 16 -1 (-850 2850)(-850 2800);
WIRE 16 -1 (-850 2850)(-650 2850);
WIRE 16 -1 (-850 2800)(-850 2750);
WIRE 16 -1 (-650 2800)(-850 2800);
WIRE 16 -1 (-850 2750)(-850 2700);
WIRE 16 -1 (-850 2750)(-650 2750);
WIRE 16 -1 (-850 2700)(-650 2700);
WIRE 16 -1 (-5200 2100)(-5200 2200);
WIRE 16 -1 (-3100 2100)(-5200 2100);
WIRE 16 -1 (-3100 2000)(-3100 2100);
WIRE 16 -1 (-2850 2100)(-3100 2100);
WIRE 16 -1 (-2850 2000)(-3100 2000);
WIRE 16 -1 (550 2900)(550 3075);
WIRE 16 -1 (550 2850)(550 2900);
WIRE 16 -1 (550 2900)(350 2900);
WIRE 16 -1 (550 2850)(350 2850);
WIRE 16 -1 (1100 1250)(1100 1350);
WIRE 16 -1 (1100 1350)(1100 1400);
WIRE 16 -1 (1100 1350)(1300 1350);
WIRE 16 -1 (1100 1400)(1100 1450);
WIRE 16 -1 (1100 1400)(1300 1400);
WIRE 16 -1 (1100 1450)(1100 1500);
WIRE 16 -1 (1100 1450)(1300 1450);
WIRE 16 -1 (1100 1500)(1100 1550);
WIRE 16 -1 (1100 1500)(1300 1500);
WIRE 16 -1 (1100 1550)(1100 1600);
WIRE 16 -1 (1100 1550)(1300 1550);
WIRE 16 -1 (1100 1600)(1100 1650);
WIRE 16 -1 (1100 1600)(1300 1600);
WIRE 16 -1 (1100 1650)(1100 1700);
WIRE 16 -1 (1100 1650)(1300 1650);
WIRE 16 -1 (1100 1700)(1100 1750);
WIRE 16 -1 (1100 1700)(1300 1700);
WIRE 16 -1 (1100 1750)(1100 1800);
WIRE 16 -1 (1100 1750)(1300 1750);
WIRE 16 -1 (1100 1800)(1100 1850);
WIRE 16 -1 (1100 1800)(1300 1800);
WIRE 16 -1 (1100 1850)(1100 1900);
WIRE 16 -1 (1100 1850)(1300 1850);
WIRE 16 -1 (1100 1900)(1100 1950);
WIRE 16 -1 (1100 1900)(1300 1900);
WIRE 16 -1 (1100 1950)(1100 2000);
WIRE 16 -1 (1100 1950)(1300 1950);
WIRE 16 -1 (1100 2000)(1100 2050);
WIRE 16 -1 (1100 2000)(1300 2000);
WIRE 16 -1 (1100 2050)(1100 2100);
WIRE 16 -1 (1100 2050)(1300 2050);
WIRE 16 -1 (1100 2100)(1100 2150);
WIRE 16 -1 (1100 2100)(1300 2100);
WIRE 16 -1 (1100 2150)(1100 2200);
WIRE 16 -1 (1100 2150)(1300 2150);
WIRE 16 -1 (1100 2200)(1100 2250);
WIRE 16 -1 (1100 2200)(1300 2200);
WIRE 16 -1 (1100 2250)(1100 2300);
WIRE 16 -1 (1100 2250)(1300 2250);
WIRE 16 -1 (1100 2300)(1100 2350);
WIRE 16 -1 (1100 2300)(1300 2300);
WIRE 16 -1 (1100 2350)(1100 2400);
WIRE 16 -1 (1100 2350)(1300 2350);
WIRE 16 -1 (1100 2400)(1100 2450);
WIRE 16 -1 (1100 2400)(1300 2400);
WIRE 16 -1 (1100 2450)(1100 2500);
WIRE 16 -1 (1100 2450)(1300 2450);
WIRE 16 -1 (1100 2500)(1100 2550);
WIRE 16 -1 (1100 2500)(1300 2500);
WIRE 16 -1 (1100 2550)(1100 2600);
WIRE 16 -1 (1100 2550)(1300 2550);
WIRE 16 -1 (1100 2600)(1100 2650);
WIRE 16 -1 (1100 2600)(1300 2600);
WIRE 16 -1 (1100 2650)(1100 2700);
WIRE 16 -1 (1100 2650)(1300 2650);
WIRE 16 -1 (1100 2700)(1100 2750);
WIRE 16 -1 (1100 2700)(1300 2700);
WIRE 16 -1 (1100 2750)(1100 2800);
WIRE 16 -1 (1100 2750)(1300 2750);
WIRE 16 -1 (1100 2800)(1100 2850);
WIRE 16 -1 (1100 2800)(1300 2800);
WIRE 16 -1 (1100 2850)(1100 2900);
WIRE 16 -1 (1100 2850)(1300 2850);
WIRE 16 -1 (1100 2900)(1100 2950);
WIRE 16 -1 (1100 2900)(1300 2900);
WIRE 16 -1 (1100 2950)(1100 3000);
WIRE 16 -1 (1100 2950)(1300 2950);
WIRE 16 -1 (1100 3000)(1100 3050);
WIRE 16 -1 (1100 3000)(1300 3000);
WIRE 16 -1 (1100 3050)(1100 3100);
WIRE 16 -1 (1100 3050)(1300 3050);
WIRE 16 -1 (1100 3100)(1100 3150);
WIRE 16 -1 (1100 3100)(1300 3100);
WIRE 16 -1 (1100 3150)(1100 3200);
WIRE 16 -1 (1100 3150)(1300 3150);
WIRE 16 -1 (1100 3200)(1100 3250);
WIRE 16 -1 (1100 3200)(1300 3200);
WIRE 16 -1 (1100 3250)(1100 3300);
WIRE 16 -1 (1100 3250)(1300 3250);
WIRE 16 -1 (1100 3300)(1100 3350);
WIRE 16 -1 (1100 3300)(1300 3300);
WIRE 16 -1 (1100 3350)(1100 3400);
WIRE 16 -1 (1100 3350)(1300 3350);
WIRE 16 -1 (1100 3400)(1100 3450);
WIRE 16 -1 (1100 3400)(1300 3400);
WIRE 16 -1 (1100 3450)(1100 3500);
WIRE 16 -1 (1100 3450)(1300 3450);
WIRE 16 -1 (1100 3500)(1100 3550);
WIRE 16 -1 (1100 3500)(1300 3500);
WIRE 16 -1 (1100 3550)(1100 3600);
WIRE 16 -1 (1100 3550)(1300 3550);
WIRE 16 -1 (1100 3600)(1100 3650);
WIRE 16 -1 (1100 3600)(1300 3600);
WIRE 16 -1 (1100 3650)(1300 3650);
WIRE 17 -1 (750 3475)(750 3575);
WIRE 17 -1 (750 3575)(750 3675);
WIRE 17 -1 (750 3675)(750 3775);
WIRE 17 -1 (750 3775)(750 3875);
WIRE 17 -1 (750 3875)(750 3975);
WIRE 17 -1 (750 3975)(750 4075);
WIRE 17 -1 (750 4075)(750 4175);
WIRE 17 -1 (750 4175)(750 4275);
WIRE 17 -1 (750 4275)(750 4375);
WIRE 17 -1 (750 4375)(750 4475);
WIRE 17 -1 (750 4475)(750 4575);
WIRE 17 -1 (750 4575)(750 4675);
WIRE 17 -1 (750 4675)(750 4775);
WIRE 17 -1 (750 4775)(750 4875);
WIRE 17 -1 (750 4875)(750 4975);
WIRE 17 -1 (750 4975)(750 5075);
WIRE 17 -1 (1550 5200)(750 5200);
FORCEPROP 2 LAST SIG_NAME M_E_DQS_DP<17:0>
J 0
(1000 5210);
DISPLAY 0.617021 (1000 5210);
PAINT ORANGE (1000 5210);
WIRE 17 -1 (750 5075)(750 5175);
WIRE 17 -1 (750 5175)(750 5200);
WIRE 17 -1 (950 3425)(950 3525);
WIRE 17 -1 (950 3525)(950 3625);
WIRE 17 -1 (950 3625)(950 3725);
WIRE 17 -1 (1550 5150)(950 5150);
FORCEPROP 2 LAST SIG_NAME M_E_DQS_DN<17:0>
J 0
(1000 5160);
DISPLAY 0.617021 (1000 5160);
PAINT ORANGE (1000 5160);
WIRE 17 -1 (950 5125)(950 5150);
WIRE 17 -1 (950 3725)(950 3825);
WIRE 17 -1 (950 3825)(950 3925);
WIRE 17 -1 (950 5025)(950 5125);
WIRE 17 -1 (950 4925)(950 5025);
WIRE 17 -1 (950 3925)(950 4025);
WIRE 17 -1 (950 4025)(950 4125);
WIRE 17 -1 (950 4825)(950 4925);
WIRE 17 -1 (950 4725)(950 4825);
WIRE 17 -1 (950 4125)(950 4225);
WIRE 17 -1 (950 4225)(950 4325);
WIRE 17 -1 (950 4625)(950 4725);
WIRE 17 -1 (950 4525)(950 4625);
WIRE 17 -1 (950 4325)(950 4425);
WIRE 17 -1 (950 4425)(950 4525);
WIRE 17 -1 (-1550 1775)(-1550 1825);
WIRE 17 -1 (-1550 1825)(-1550 1875);
WIRE 17 -1 (-1550 1875)(-1550 1925);
WIRE 17 -1 (-1550 1925)(-1550 1975);
WIRE 17 -1 (-1550 1975)(-1550 2025);
WIRE 17 -1 (-1550 2025)(-1550 2075);
WIRE 17 -1 (-1550 2075)(-1550 2125);
WIRE 17 -1 (-1550 2125)(-1550 2175);
WIRE 17 -1 (-1550 2175)(-1550 2225);
WIRE 17 -1 (-1550 2225)(-1550 2275);
WIRE 17 -1 (-1550 2275)(-1550 2325);
WIRE 17 -1 (-1550 2325)(-1550 2375);
WIRE 17 -1 (-1550 2375)(-1550 2425);
WIRE 17 -1 (-1550 2425)(-1550 2475);
WIRE 17 -1 (-1550 2475)(-1550 2525);
WIRE 17 -1 (-1550 2525)(-1550 2575);
WIRE 17 -1 (-1550 2575)(-1550 2625);
WIRE 17 -1 (-1550 2625)(-1550 2675);
WIRE 17 -1 (-1550 2675)(-1550 2725);
WIRE 17 -1 (-1550 2725)(-1550 2775);
WIRE 17 -1 (-1550 2775)(-1550 2825);
WIRE 17 -1 (-1550 2825)(-1550 2875);
WIRE 17 -1 (-1550 2875)(-1550 2925);
WIRE 17 -1 (-1550 2925)(-1550 2975);
WIRE 17 -1 (-1550 2975)(-1550 3025);
WIRE 17 -1 (-1550 3025)(-1550 3075);
WIRE 17 -1 (-1550 3075)(-1550 3125);
WIRE 17 -1 (-1550 3125)(-1550 3175);
WIRE 17 -1 (-1550 3175)(-1550 3225);
WIRE 17 -1 (-1550 3225)(-1550 3275);
WIRE 17 -1 (-1550 3275)(-1550 3325);
WIRE 17 -1 (-1550 3325)(-1550 3375);
WIRE 17 -1 (-1550 3375)(-1550 3425);
WIRE 17 -1 (-1550 3425)(-1550 3475);
WIRE 17 -1 (-1550 3475)(-1550 3525);
WIRE 17 -1 (-1550 3525)(-1550 3575);
WIRE 17 -1 (-1550 3575)(-1550 3625);
WIRE 17 -1 (-1550 3625)(-1550 3675);
WIRE 17 -1 (-1550 3675)(-1550 3725);
WIRE 17 -1 (-1550 3725)(-1550 3775);
WIRE 17 -1 (-1550 3775)(-1550 3825);
WIRE 17 -1 (-1550 3825)(-1550 3875);
WIRE 17 -1 (-1550 3875)(-1550 3925);
WIRE 17 -1 (-1550 3925)(-1550 3975);
WIRE 17 -1 (-1550 3975)(-1550 4025);
WIRE 17 -1 (-1550 4025)(-1550 4075);
WIRE 17 -1 (-1550 4075)(-1550 4125);
WIRE 17 -1 (-1550 4125)(-1550 4175);
WIRE 17 -1 (-1550 4175)(-1550 4225);
WIRE 17 -1 (-1550 4225)(-1550 4275);
WIRE 17 -1 (-1550 4275)(-1550 4325);
WIRE 17 -1 (-1550 4325)(-1550 4375);
WIRE 17 -1 (-1550 4375)(-1550 4425);
WIRE 17 -1 (-1550 4425)(-1550 4475);
WIRE 17 -1 (-1550 4475)(-1550 4525);
WIRE 17 -1 (-1550 4525)(-1550 4575);
WIRE 17 -1 (-1550 4575)(-1550 4625);
WIRE 17 -1 (-1100 4950)(-1550 4950);
FORCEPROP 2 LAST SIG_NAME M_E_DQ<63:0>
J 0
(-1510 4960);
DISPLAY 0.617021 (-1510 4960);
PAINT ORANGE (-1510 4960);
WIRE 17 -1 (-1550 4925)(-1550 4950);
WIRE 17 -1 (-1550 4625)(-1550 4675);
WIRE 17 -1 (-1550 4675)(-1550 4725);
WIRE 17 -1 (-1550 4875)(-1550 4925);
WIRE 17 -1 (-1550 4825)(-1550 4875);
WIRE 17 -1 (-1550 4725)(-1550 4775);
WIRE 17 -1 (-1550 4775)(-1550 4825);
WIRE 17 -1 (-3150 4075)(-3150 4125);
WIRE 17 -1 (-3150 4125)(-3150 4175);
WIRE 17 -1 (-3150 4175)(-3150 4225);
WIRE 17 -1 (-3150 4225)(-3150 4275);
WIRE 17 -1 (-3150 4275)(-3150 4325);
WIRE 17 -1 (-3150 4325)(-3150 4375);
WIRE 17 -1 (-3150 4375)(-3150 4425);
WIRE 17 -1 (-3150 4425)(-3150 4475);
WIRE 17 -1 (-3150 4475)(-3150 4525);
WIRE 17 -1 (-3150 4525)(-3150 4575);
WIRE 17 -1 (-3150 4575)(-3150 4625);
WIRE 17 -1 (-3150 4625)(-3150 4675);
WIRE 17 -1 (-3150 4675)(-3150 4725);
WIRE 17 -1 (-3150 4725)(-3150 4775);
WIRE 17 -1 (-3150 4775)(-3150 4825);
WIRE 17 -1 (-3850 4950)(-3150 4950);
FORCEPROP 2 LAST SIG_NAME M_E_MA<17:0>
J 0
(-3800 4960);
DISPLAY 0.617021 (-3800 4960);
PAINT ORANGE (-3800 4960);
WIRE 17 -1 (-3150 4925)(-3150 4950);
WIRE 17 -1 (-3150 4825)(-3150 4875);
WIRE 17 -1 (-3150 4875)(-3150 4925);
WIRE 17 -1 (-3150 3925)(-3150 3975);
WIRE 17 -1 (-3150 4050)(-3850 4050);
FORCEPROP 2 LAST SIG_NAME M_E_BA<1:0>
J 0
(-3800 4060);
DISPLAY 0.617021 (-3800 4060);
PAINT ORANGE (-3800 4060);
WIRE 17 -1 (-3150 4050)(-3150 3975);
WIRE 17 -1 (-3150 3900)(-3850 3900);
FORCEPROP 2 LAST SIG_NAME M_E_BG<1:0>
J 0
(-3800 3910);
DISPLAY 0.617021 (-3800 3910);
PAINT ORANGE (-3800 3910);
WIRE 17 -1 (-3150 3825)(-3150 3875);
WIRE 17 -1 (-3150 3875)(-3150 3900);
WIRE 17 -1 (-3150 3275)(-3150 3325);
WIRE 17 -1 (-3150 3450)(-3850 3450);
FORCEPROP 2 LAST SIG_NAME M_E_CS_N<7:0>
J 0
(-3825 3460);
DISPLAY 0.617021 (-3825 3460);
PAINT ORANGE (-3825 3460);
WIRE 17 -1 (-3150 3425)(-3150 3450);
WIRE 17 -1 (-3150 3325)(-3150 3375);
WIRE 17 -1 (-3150 3375)(-3150 3425);
WIRE 17 -1 (-3150 2525)(-3150 2575);
WIRE 17 -1 (-3150 2575)(-3150 2625);
WIRE 17 -1 (-3150 2625)(-3150 2675);
WIRE 17 -1 (-3150 2675)(-3150 2725);
WIRE 17 -1 (-3150 2725)(-3150 2775);
WIRE 17 -1 (-3150 2900)(-3850 2900);
FORCEPROP 2 LAST SIG_NAME M_E_ECC<7:0>
J 0
(-3825 2910);
DISPLAY 0.617021 (-3825 2910);
PAINT ORANGE (-3825 2910);
WIRE 17 -1 (-3150 2875)(-3150 2900);
WIRE 17 -1 (-3150 2775)(-3150 2825);
WIRE 17 -1 (-3150 2825)(-3150 2875);
WIRE 17 -1 (-3150 3050)(-3850 3050);
FORCEPROP 2 LAST SIG_NAME M_E_ODT<3:0>
J 0
(-3825 3060);
DISPLAY 0.617021 (-3825 3060);
PAINT ORANGE (-3825 3060);
WIRE 17 -1 (-3150 3025)(-3150 3050);
WIRE 17 -1 (-3150 2975)(-3150 3025);
WIRE 17 -1 (-3700 3750)(-4150 3750);
FORCEPROP 2 LAST SIG_NAME M_E_CLK_DN<3:0>
J 0
(-4125 3760);
DISPLAY 0.617021 (-4125 3760);
PAINT ORANGE (-4125 3760);
WIRE 17 -1 (-3700 3575)(-3700 3675);
WIRE 17 -1 (-3700 3675)(-3700 3750);
WIRE 17 -1 (-3550 3800)(-4150 3800);
FORCEPROP 2 LAST SIG_NAME M_E_CLK_DP<3:0>
J 0
(-4125 3810);
DISPLAY 0.617021 (-4125 3810);
PAINT ORANGE (-4125 3810);
WIRE 17 -1 (-3550 3800)(-3550 3725);
WIRE 17 -1 (-3550 3725)(-3550 3625);
WIRE 17 -1 (-3200 3200)(-3850 3200);
FORCEPROP 2 LAST SIG_NAME M_E_CKE<3:0>
J 0
(-3825 3210);
DISPLAY 0.617021 (-3825 3210);
PAINT ORANGE (-3825 3210);
WIRE 17 -1 (-3200 3125)(-3200 3175);
WIRE 17 -1 (-3200 3175)(-3200 3200);
WIRE 16 -1 (-3700 1650)(-2850 1650);
FORCEPROP 2 LAST SIG_NAME TP_CH_E_DIMM_E0_RFU_2
J 0
(-3650 1660);
DISPLAY 0.617021 (-3650 1660);
PAINT ORANGE (-3650 1660);
FORCEPROP 2 LASTPROP $XRERR UNIQUE?
J 0
(-3940 1650);
DISPLAY 0.638298 (-3940 1650);
PAINT MONO (-3940 1650);
DISPLAY INVISIBLE (-3940 1650);
WIRE 16 -1 (-1650 4100)(-1850 4100);
WIRE 16 -1 (-1650 4150)(-1850 4150);
WIRE 16 -1 (-3700 1450)(-2850 1450);
FORCEPROP 2 LAST SIG_NAME FM_ADR_COMPLETE_DEF_N
J 0
(-3650 1460);
DISPLAY 0.617021 (-3650 1460);
PAINT ORANGE (-3650 1460);
WIRE 16 -1 (-2850 4450)(-3050 4450);
WIRE 16 -1 (-1650 4350)(-1850 4350);
WIRE 16 -1 (-1650 2250)(-1850 2250);
WIRE 16 -1 (-1650 2200)(-1850 2200);
WIRE 16 -1 (-1650 2150)(-1850 2150);
WIRE 16 -1 (-3700 1600)(-2850 1600);
FORCEPROP 2 LAST SIG_NAME TP_CH_E_DIMM_E0_RFU_1
J 0
(-3650 1610);
DISPLAY 0.617021 (-3650 1610);
PAINT ORANGE (-3650 1610);
FORCEPROP 2 LASTPROP $XRERR UNIQUE?
J 0
(-3940 1600);
DISPLAY 0.638298 (-3940 1600);
PAINT MONO (-3940 1600);
DISPLAY INVISIBLE (-3940 1600);
WIRE 16 -1 (-3700 1550)(-2850 1550);
FORCEPROP 2 LAST SIG_NAME TP_CH_E_DIMM_E0_RFU_0
J 0
(-3650 1560);
DISPLAY 0.617021 (-3650 1560);
PAINT ORANGE (-3650 1560);
FORCEPROP 2 LASTPROP $XRERR UNIQUE?
J 0
(-3940 1550);
DISPLAY 0.638298 (-3940 1550);
PAINT MONO (-3940 1550);
DISPLAY INVISIBLE (-3940 1550);
WIRE 16 -1 (-4750 1750)(-4650 1750);
WIRE 16 -1 (-4650 1750)(-4650 1650);
WIRE 16 -1 (-2850 1750)(-4650 1750);
FORCEPROP 2 LAST SIG_NAME M_E_VREF
J 0
(-3600 1760);
DISPLAY 0.617021 (-3600 1760);
PAINT ORANGE (-3600 1760);
WIRE 16 -1 (-3650 1850)(-2850 1850);
FORCEPROP 2 LAST SIG_NAME SMB_DDR_DEF_VPP_SCL
J 0
(-3610 1860);
DISPLAY 0.617021 (-3610 1860);
PAINT ORANGE (-3610 1860);
WIRE 16 -1 (-2850 1900)(-3650 1900);
WIRE 16 -1 (-3300 2600)(-4025 2600);
FORCEPROP 2 LAST SIG_NAME FM_DIMM_EVENT_COD_N
J 0
(-3958 2624);
DISPLAY 0.617021 (-3958 2624);
PAINT ORANGE (-3958 2624);
WIRE 16 -1 (-3300 2300)(-3300 2600);
WIRE 16 -1 (-3300 2300)(-2850 2300);
WIRE 16 -1 (-3250 2800)(-3850 2800);
FORCEPROP 2 LAST SIG_NAME M_DEF_RST_N
J 0
(-3825 2810);
DISPLAY 0.617021 (-3825 2810);
PAINT ORANGE (-3825 2810);
WIRE 16 -1 (-3250 2350)(-3250 2800);
WIRE 16 -1 (-2850 2350)(-3250 2350);
WIRE 16 -1 (-3200 2850)(-3850 2850);
FORCEPROP 2 LAST SIG_NAME M_E_PAR
J 0
(-3825 2860);
DISPLAY 0.617021 (-3825 2860);
PAINT ORANGE (-3825 2860);
WIRE 16 -1 (-3200 2400)(-3200 2850);
WIRE 16 -1 (-2850 2400)(-3200 2400);
WIRE 16 -1 (-2850 3100)(-3100 3100);
WIRE 16 -1 (-2850 3700)(-3450 3700);
WIRE 16 -1 (-2850 3150)(-3100 3150);
WIRE 16 -1 (-2850 3600)(-3450 3600);
WIRE 16 -1 (-2850 3550)(-3600 3550);
WIRE 16 -1 (-2850 3650)(-3600 3650);
WIRE 16 -1 (-2850 2200)(-3850 2200);
FORCEPROP 2 LAST SIG_NAME M_E_ACT_N
J 0
(-3800 2210);
DISPLAY 0.617021 (-3800 2210);
PAINT ORANGE (-3800 2210);
WIRE 16 -1 (-2850 2250)(-3875 2250);
FORCEPROP 2 LAST SIG_NAME M_E_ALERT_N
J 0
(-3825 2260);
DISPLAY 0.617021 (-3825 2260);
PAINT ORANGE (-3825 2260);
WIRE 16 -1 (-2850 2500)(-3050 2500);
WIRE 16 -1 (-2850 2550)(-3050 2550);
WIRE 16 -1 (-2850 2600)(-3050 2600);
WIRE 16 -1 (-2850 2650)(-3050 2650);
WIRE 16 -1 (-2850 2700)(-3050 2700);
WIRE 16 -1 (-2850 2750)(-3050 2750);
WIRE 16 -1 (-2850 2800)(-3050 2800);
WIRE 16 -1 (-2850 3000)(-3050 3000);
WIRE 16 -1 (-2850 2950)(-3050 2950);
WIRE 16 -1 (-2850 2850)(-3050 2850);
WIRE 16 -1 (-2850 3250)(-3050 3250);
WIRE 16 -1 (-2850 3300)(-3050 3300);
WIRE 16 -1 (-3000 3500)(-3850 3500);
FORCEPROP 2 LAST SIG_NAME M_E_C<2>
J 0
(-3825 3510);
DISPLAY 0.617021 (-3825 3510);
PAINT ORANGE (-3825 3510);
WIRE 16 -1 (-3000 3500)(-3000 3450);
WIRE 16 -1 (-3000 3450)(-2850 3450);
WIRE 16 -1 (-2850 3350)(-3050 3350);
WIRE 16 -1 (-2850 3400)(-3050 3400);
WIRE 16 -1 (-2850 3800)(-3050 3800);
WIRE 16 -1 (-2850 3900)(-3050 3900);
WIRE 16 -1 (-2850 3850)(-3050 3850);
WIRE 16 -1 (-2850 4050)(-3050 4050);
WIRE 16 -1 (-2850 3950)(-3050 3950);
WIRE 16 -1 (-1650 2000)(-1850 2000);
WIRE 16 -1 (-1650 1950)(-1850 1950);
WIRE 16 -1 (-1650 1900)(-1850 1900);
WIRE 16 -1 (-1650 1850)(-1850 1850);
WIRE 16 -1 (-1650 1750)(-1850 1750);
WIRE 16 -1 (-1650 1800)(-1850 1800);
WIRE 16 -1 (-1650 2500)(-1850 2500);
WIRE 16 -1 (-1650 2050)(-1850 2050);
WIRE 16 -1 (-1650 2100)(-1850 2100);
WIRE 16 -1 (-1650 2300)(-1850 2300);
WIRE 16 -1 (-1650 2350)(-1850 2350);
WIRE 16 -1 (-1650 2450)(-1850 2450);
WIRE 16 -1 (-1650 2550)(-1850 2550);
WIRE 16 -1 (-1650 2400)(-1850 2400);
WIRE 16 -1 (-1650 2600)(-1850 2600);
WIRE 16 -1 (-1650 3050)(-1850 3050);
WIRE 16 -1 (-1650 2650)(-1850 2650);
WIRE 16 -1 (-1650 2700)(-1850 2700);
WIRE 16 -1 (-1650 2750)(-1850 2750);
WIRE 16 -1 (-1650 2850)(-1850 2850);
WIRE 16 -1 (-1650 2900)(-1850 2900);
WIRE 16 -1 (-1650 2950)(-1850 2950);
WIRE 16 -1 (-1650 3000)(-1850 3000);
WIRE 16 -1 (-1650 2800)(-1850 2800);
WIRE 16 -1 (-1650 3100)(-1850 3100);
WIRE 16 -1 (-1650 3550)(-1850 3550);
WIRE 16 -1 (-1650 3500)(-1850 3500);
WIRE 16 -1 (-1650 3250)(-1850 3250);
WIRE 16 -1 (-1650 3300)(-1850 3300);
WIRE 16 -1 (-1650 3350)(-1850 3350);
WIRE 16 -1 (-1650 3400)(-1850 3400);
WIRE 16 -1 (-1650 3450)(-1850 3450);
WIRE 16 -1 (-1650 3150)(-1850 3150);
WIRE 16 -1 (-1650 3200)(-1850 3200);
WIRE 16 -1 (-1650 3650)(-1850 3650);
WIRE 16 -1 (-1650 3600)(-1850 3600);
WIRE 16 -1 (-1650 3700)(-1850 3700);
WIRE 16 -1 (-1650 3750)(-1850 3750);
WIRE 16 -1 (-1650 3800)(-1850 3800);
WIRE 16 -1 (-1650 3850)(-1850 3850);
WIRE 16 -1 (-1650 3900)(-1850 3900);
WIRE 16 -1 (-1650 3950)(-1850 3950);
WIRE 16 -1 (-1650 4000)(-1850 4000);
WIRE 16 -1 (-1650 4050)(-1850 4050);
WIRE 16 -1 (-2850 4150)(-3050 4150);
WIRE 16 -1 (-2850 4350)(-3050 4350);
WIRE 16 -1 (-2850 4300)(-3050 4300);
WIRE 16 -1 (-2850 4250)(-3050 4250);
WIRE 16 -1 (-2850 4200)(-3050 4200);
WIRE 16 -1 (-2850 4100)(-3050 4100);
WIRE 16 -1 (-2850 4600)(-3050 4600);
WIRE 16 -1 (-2850 4550)(-3050 4550);
WIRE 16 -1 (-2850 4500)(-3050 4500);
WIRE 16 -1 (-2850 4400)(-3050 4400);
WIRE 16 -1 (-2850 4850)(-3050 4850);
WIRE 16 -1 (-2850 4800)(-3050 4800);
WIRE 16 -1 (-2850 4750)(-3050 4750);
WIRE 16 -1 (-2850 4700)(-3050 4700);
WIRE 16 -1 (-2850 4650)(-3050 4650);
WIRE 16 -1 (-2850 4900)(-3050 4900);
WIRE 16 -1 (-1650 4200)(-1850 4200);
WIRE 16 -1 (-1650 4250)(-1850 4250);
WIRE 16 -1 (-1650 4300)(-1850 4300);
WIRE 16 -1 (-1650 4400)(-1850 4400);
WIRE 16 -1 (-1650 4450)(-1850 4450);
WIRE 16 -1 (-1650 4600)(-1850 4600);
WIRE 16 -1 (-1650 4500)(-1850 4500);
WIRE 16 -1 (-1650 4550)(-1850 4550);
WIRE 16 -1 (-1650 4900)(-1850 4900);
WIRE 16 -1 (-1650 4850)(-1850 4850);
WIRE 16 -1 (-1650 4800)(-1850 4800);
WIRE 16 -1 (-1650 4650)(-1850 4650);
WIRE 16 -1 (-1650 4700)(-1850 4700);
WIRE 16 -1 (-1650 4750)(-1850 4750);
WIRE 16 -1 (650 4050)(450 4050);
WIRE 16 -1 (850 4000)(450 4000);
WIRE 16 -1 (650 3950)(450 3950);
WIRE 16 -1 (850 3900)(450 3900);
WIRE 16 -1 (650 3850)(450 3850);
WIRE 16 -1 (850 3800)(450 3800);
WIRE 16 -1 (650 3750)(450 3750);
WIRE 16 -1 (850 3700)(450 3700);
WIRE 16 -1 (650 3650)(450 3650);
WIRE 16 -1 (850 3600)(450 3600);
WIRE 16 -1 (650 3550)(450 3550);
WIRE 16 -1 (850 3500)(450 3500);
WIRE 16 -1 (650 3450)(450 3450);
WIRE 16 -1 (850 3400)(450 3400);
WIRE 16 -1 (650 4350)(450 4350);
WIRE 16 -1 (850 4300)(450 4300);
WIRE 16 -1 (650 4250)(450 4250);
WIRE 16 -1 (850 4200)(450 4200);
WIRE 16 -1 (650 4150)(450 4150);
WIRE 16 -1 (850 4100)(450 4100);
WIRE 16 -1 (850 5100)(450 5100);
WIRE 16 -1 (650 5050)(450 5050);
WIRE 16 -1 (850 5000)(450 5000);
WIRE 16 -1 (650 4950)(450 4950);
WIRE 16 -1 (850 4900)(450 4900);
WIRE 16 -1 (650 4850)(450 4850);
WIRE 16 -1 (850 4800)(450 4800);
WIRE 16 -1 (650 4750)(450 4750);
WIRE 16 -1 (850 4700)(450 4700);
WIRE 16 -1 (650 4650)(450 4650);
WIRE 16 -1 (850 4600)(450 4600);
WIRE 16 -1 (650 4550)(450 4550);
WIRE 16 -1 (850 4500)(450 4500);
WIRE 16 -1 (650 4450)(450 4450);
WIRE 16 -1 (850 4400)(450 4400);
WIRE 16 -1 (650 5150)(450 5150);
DOT 1 (-850 1600);
DOT 1 (1100 2450);
DOT 1 (2500 2950);
DOT 1 (-850 2000);
DOT 1 (-3250 1950);
DOT 1 (-850 2450);
DOT 1 (-850 2900);
DOT 1 (1100 2700);
DOT 1 (-850 1550);
DOT 1 (-850 2050);
DOT 1 (1100 3350);
DOT 1 (-850 2850);
DOT 1 (-4650 1750);
DOT 1 (-3100 2100);
DOT 1 (1100 1350);
DOT 1 (1100 1400);
DOT 1 (1100 1450);
DOT 1 (1100 1500);
DOT 1 (1100 1550);
DOT 1 (1100 1600);
DOT 1 (1100 1650);
DOT 1 (1100 1700);
DOT 1 (1100 1800);
DOT 1 (1100 1900);
DOT 1 (1100 1950);
DOT 1 (1100 2000);
DOT 1 (1100 2050);
DOT 1 (1100 2150);
DOT 1 (1100 2200);
DOT 1 (1100 2250);
DOT 1 (1100 2300);
DOT 1 (1100 2350);
DOT 1 (1100 2400);
DOT 1 (1100 2500);
DOT 1 (1100 2550);
DOT 1 (1100 2600);
DOT 1 (1100 2650);
DOT 1 (1100 2750);
DOT 1 (1100 2800);
DOT 1 (1100 2850);
DOT 1 (1100 2900);
DOT 1 (1100 2950);
DOT 1 (1100 3000);
DOT 1 (1100 3050);
DOT 1 (1100 3100);
DOT 1 (1100 3150);
DOT 1 (1100 3200);
DOT 1 (1100 3250);
DOT 1 (1100 3300);
DOT 1 (1100 3400);
DOT 1 (1100 3450);
DOT 1 (1100 3500);
DOT 1 (1100 3550);
DOT 1 (1100 3600);
DOT 1 (2500 1350);
DOT 1 (2500 1400);
DOT 1 (2500 1450);
DOT 1 (2500 1500);
DOT 1 (2500 1550);
DOT 1 (2500 1600);
DOT 1 (2500 1650);
DOT 1 (2500 1700);
DOT 1 (2500 1750);
DOT 1 (2500 1800);
DOT 1 (2500 1900);
DOT 1 (2500 1850);
DOT 1 (2500 1950);
DOT 1 (2500 2000);
DOT 1 (2500 2050);
DOT 1 (2500 2150);
DOT 1 (2500 2100);
DOT 1 (2500 2250);
DOT 1 (2500 2300);
DOT 1 (2500 2200);
DOT 1 (2500 2350);
DOT 1 (2500 2400);
DOT 1 (2500 2450);
DOT 1 (2500 2600);
DOT 1 (2500 2650);
DOT 1 (2500 2700);
DOT 1 (2500 2800);
DOT 1 (2500 2750);
DOT 1 (2500 2850);
DOT 1 (2500 2900);
DOT 1 (2500 3050);
DOT 1 (2500 3000);
DOT 1 (2500 3150);
DOT 1 (2500 3100);
DOT 1 (2500 3200);
DOT 1 (2500 3250);
DOT 1 (2500 3300);
DOT 1 (2500 3400);
DOT 1 (2500 3450);
DOT 1 (2500 3350);
DOT 1 (2500 3500);
DOT 1 (2500 3550);
DOT 1 (2500 3600);
DOT 1 (-850 2800);
DOT 1 (-850 2750);
DOT 1 (-850 2600);
DOT 1 (-850 2300);
DOT 1 (-850 2250);
DOT 1 (-850 2200);
DOT 1 (-850 2150);
DOT 1 (-850 2100);
DOT 1 (-850 1900);
DOT 1 (-850 1800);
DOT 1 (-850 1850);
DOT 1 (-850 1750);
DOT 1 (-850 1650);
DOT 1 (-850 1700);
DOT 1 (-850 1500);
DOT 1 (-850 1300);
DOT 1 (-850 1250);
DOT 1 (-850 1950);
DOT 1 (550 2900);
DOT 1 (1100 1750);
DOT 1 (2500 2500);
DOT 1 (2500 2550);
DOT 1 (-850 2350);
DOT 1 (-850 1450);
DOT 1 (-850 1400);
DOT 1 (-850 1350);
DOT 1 (-850 2400);
DOT 1 (1100 1850);
DOT 1 (1100 2100);
FORCENOTE
PVDDQ (SINGLE SIDE) CAP: 10UF X1, 22UF X50
(-3150 925) 0;
DISPLAY LEFT (-3150 925);
DISPLAY 1.021277 (-3150 925);
PAINT PURPLE (-3150 925);
FORCENOTE
PVTT CAP: 100UF X2, 47UF X1
(-3150 975) 0;
DISPLAY LEFT (-3150 975);
DISPLAY 1.021277 (-3150 975);
PAINT PURPLE (-3150 975);
FORCENOTE
PVPP CAP: 10UF X12
(-3150 1025) 0;
DISPLAY LEFT (-3150 1025);
DISPLAY 1.021277 (-3150 1025);
PAINT PURPLE (-3150 1025);
FORCENOTE
CAP BETWEEN DIMM
(-3150 1100) 0;
DISPLAY LEFT (-3150 1100);
DISPLAY 1.276596 (-3150 1100);
PAINT PURPLE (-3150 1100);
FORCENOTE
PVDDQ (DOUBLE SIDE) CAP: 100UF X8, 47UF X41
(-3150 875) 0;
DISPLAY LEFT (-3150 875);
DISPLAY 1.021277 (-3150 875);
PAINT PURPLE (-3150 875);
FORCENOTE
SMBUS ADDR: 0XA4
(-5275 709) 0;
DISPLAY LEFT (-5275 709);
DISPLAY 1.957447 (-5275 709);
PAINT PURPLE (-5275 709);
FORCENOTE
PLACE CAP NEAR DIMM CONNECTOR
(-5263 1152) 0;
DISPLAY LEFT (-5263 1152);
DISPLAY 1.595745 (-5263 1152);
PAINT PURPLE (-5263 1152);
QUIT
